FILE_TYPE = MACRO_DRAWING;
SET COLOR_WIRE YELLOW;
SET COLOR_PROP ORANGE;
SET COLOR_DOT WHITE;
SET COLOR_ARC YELLOW;
SET COLOR_BODY GREEN;
SET COLOR_NOTE PURPLE;
SET PROP_DISPLAY VALUE;
SET PAGE_NUMBER P332;
FORCEADD UNIVERSAL_GND..1
(-2050 -1475);
FORCEPROP 3 LASTPIN (-2050 -1425) SIG_NAME GND\g
J 0
(-2040 -1415);
DISPLAY 0.659574 (-2040 -1415);
PAINT MONO (-2040 -1415);
DISPLAY INVISIBLE (-2040 -1415);
FORCEPROP 2 LAST CDS_LIB pure_quanta_power
J 0
(-2050 -1475);
DISPLAY INVISIBLE (-2050 -1475);
FORCEPROP 1 LAST HDL_POWER GND
J 1
(-2025 -1550);
DISPLAY 0.872340 (-2025 -1550);
PAINT GREEN (-2025 -1550);
DISPLAY INVISIBLE (-2025 -1550);
FORCEPROP 1 LAST PATH I1
J 0
(-1975 -1475);
DISPLAY 0.872340 (-1975 -1475);
PAINT AQUA (-1975 -1475);
DISPLAY INVISIBLE (-1975 -1475);
FORCEADD MOSFET_NCH_DUAL..2
(200 -650);
FORCEPROP 1 LAST LOCATION Q134
J 0
(351 -674);
DISPLAY 0.723404 (351 -674);
PAINT GREEN (351 -674);
FORCEPROP 0 LAST $SEC 2
J 0
(375 -525);
DISPLAY 0.680851 (375 -525);
PAINT MONO (375 -525);
DISPLAY INVISIBLE (375 -525);
FORCEPROP 0 LAST CDS_SEC 2
J 0
(375 -525);
DISPLAY 1.021277 (375 -525);
DISPLAY INVISIBLE (375 -525);
FORCEPROP 0 LASTPIN (250 -450) $PN 3
R 1
J 0
(240 -440);
DISPLAY 0.680851 (240 -440);
PAINT MONO (240 -440);
FORCEPROP 0 LASTPIN (0 -700) $PN 5
J 2
(-10 -690);
DISPLAY 0.680851 (-10 -690);
PAINT MONO (-10 -690);
FORCEPROP 0 LASTPIN (250 -850) $PN 4
R 1
J 2
(240 -860);
DISPLAY 0.680851 (240 -860);
PAINT MONO (240 -860);
FORCEPROP 1 LAST MATERIAL IC
J 0
(351 -799);
DISPLAY 0.723404 (351 -799);
PAINT GREEN (351 -799);
FORCEPROP 2 LAST VALUE PJT138K
J 0
(375 -625);
DISPLAY 1.021277 (375 -625);
FORCEPROP 2 LAST PART_TYPE SMLF
J 0
(375 -575);
DISPLAY 1.021277 (375 -575);
FORCEPROP 1 LAST CDS_LMAN_SYM_OUTLINE -150,150,150,-150
J 0
(200 -650);
DISPLAY 0.468085 (200 -650);
PAINT GREEN (200 -650);
DISPLAY INVISIBLE (200 -650);
FORCEPROP 1 LAST NEEDS_NO_SIZE TRUE
J 0
(350 -759);
DISPLAY 0.468085 (350 -759);
PAINT GREEN (350 -759);
DISPLAY INVISIBLE (350 -759);
FORCEPROP 2 LAST CDS_LIB pure_quanta
J 0
(200 -650);
DISPLAY INVISIBLE (200 -650);
FORCEPROP 1 LAST PATH I10
J 0
(350 -800);
DISPLAY 0.723404 (350 -800);
PAINT GREEN (350 -800);
DISPLAY INVISIBLE (350 -800);
FORCEPROP 1 LAST PART_NUMBER BAM138K0003
J 0
(351 -744);
DISPLAY 0.723404 (351 -744);
PAINT GREEN (351 -744);
DISPLAY INVISIBLE (351 -744);
FORCEADD UNIVERSAL_POWER..1
(3675 3175);
FORCEPROP 3 LASTPIN (3675 3125) SIG_NAME P3V3_AUX\g
J 0
(3685 3135);
DISPLAY 0.659574 (3685 3135);
PAINT MONO (3685 3135);
DISPLAY INVISIBLE (3685 3135);
FORCEPROP 1 LAST HDL_POWER P3V3_AUX
J 1
(3675 3225);
DISPLAY 0.872340 (3675 3225);
PAINT GREEN (3675 3225);
FORCEPROP 2 LAST CDS_LIB pure_quanta_power
J 0
(3675 3175);
PAINT MONO (3675 3175);
DISPLAY INVISIBLE (3675 3175);
FORCEPROP 1 LAST PATH I100
J 0
(3725 3200);
DISPLAY 0.872340 (3725 3200);
PAINT AQUA (3725 3200);
DISPLAY INVISIBLE (3725 3200);
FORCEADD UNIVERSAL_GND..1
(3650 3350);
FORCEPROP 3 LASTPIN (3650 3400) SIG_NAME GND\g
J 0
(3660 3410);
DISPLAY 0.659574 (3660 3410);
PAINT MONO (3660 3410);
DISPLAY INVISIBLE (3660 3410);
FORCEPROP 2 LAST CDS_LIB pure_quanta_power
J 0
(3650 3350);
DISPLAY INVISIBLE (3650 3350);
FORCEPROP 1 LAST HDL_POWER GND
J 1
(3675 3275);
DISPLAY 0.872340 (3675 3275);
PAINT GREEN (3675 3275);
DISPLAY INVISIBLE (3675 3275);
FORCEPROP 1 LAST PATH I101
J 0
(3725 3350);
DISPLAY 0.872340 (3725 3350);
PAINT AQUA (3725 3350);
DISPLAY INVISIBLE (3725 3350);
FORCEADD MOSFET_NCH_DUAL..1
(3600 3725);
FORCEPROP 1 LAST LOCATION Q130
J 0
(3751 3699);
DISPLAY 0.723404 (3751 3699);
PAINT GREEN (3751 3699);
FORCEPROP 0 LAST $SEC 1
J 0
(3775 3850);
DISPLAY 0.680851 (3775 3850);
PAINT MONO (3775 3850);
DISPLAY INVISIBLE (3775 3850);
FORCEPROP 2 LAST CDS_SEC 1
J 0
(3775 3850);
DISPLAY 1.021277 (3775 3850);
DISPLAY INVISIBLE (3775 3850);
FORCEPROP 0 LASTPIN (3650 3925) $PN 6
R 1
J 0
(3640 3935);
DISPLAY 0.680851 (3640 3935);
PAINT MONO (3640 3935);
FORCEPROP 0 LASTPIN (3400 3675) $PN 2
J 2
(3390 3685);
DISPLAY 0.680851 (3390 3685);
PAINT MONO (3390 3685);
FORCEPROP 0 LASTPIN (3650 3525) $PN 1
R 1
J 2
(3640 3515);
DISPLAY 0.680851 (3640 3515);
PAINT MONO (3640 3515);
FORCEPROP 2 LAST VALUE PJT138K
J 0
(3775 3750);
DISPLAY 1.021277 (3775 3750);
FORCEPROP 2 LAST PART_TYPE SMLF
J 0
(3775 3800);
DISPLAY 1.021277 (3775 3800);
FORCEPROP 1 LAST MATERIAL IC
J 0
(3751 3574);
DISPLAY 0.723404 (3751 3574);
PAINT GREEN (3751 3574);
FORCEPROP 2 LAST CDS_LIB pure_quanta
J 0
(3600 3725);
DISPLAY INVISIBLE (3600 3725);
FORCEPROP 1 LAST NEEDS_NO_SIZE TRUE
J 0
(3600 3724);
DISPLAY 0.468085 (3600 3724);
PAINT GREEN (3600 3724);
DISPLAY INVISIBLE (3600 3724);
FORCEPROP 1 LAST CDS_LMAN_SYM_OUTLINE -150,150,150,-150
J 0
(3600 3725);
DISPLAY 0.468085 (3600 3725);
PAINT GREEN (3600 3725);
DISPLAY INVISIBLE (3600 3725);
FORCEPROP 1 LAST PATH I102
J 0
(3600 3725);
DISPLAY 0.723404 (3600 3725);
PAINT GREEN (3600 3725);
DISPLAY INVISIBLE (3600 3725);
FORCEPROP 1 LAST PART_NUMBER BAM138K0003
J 0
(3751 3639);
DISPLAY 0.723404 (3751 3639);
PAINT GREEN (3751 3639);
DISPLAY INVISIBLE (3751 3639);
FORCEADD Q_RES..1
(4000 3325);
FORCEPROP 1 LAST LOCATION R4578
J 0
(3750 3325);
DISPLAY 0.787234 (3750 3325);
FORCEPROP 0 LAST $SEC 1
J 0
(4250 3450);
DISPLAY 0.680851 (4250 3450);
PAINT MONO (4250 3450);
DISPLAY INVISIBLE (4250 3450);
FORCEPROP 0 LAST CDS_SEC 1
J 0
(4250 3450);
DISPLAY 1.021277 (4250 3450);
DISPLAY INVISIBLE (4250 3450);
FORCEPROP 1 LASTPIN (3900 3325) $PN 1
J 0
(3912 3337);
DISPLAY 0.787234 (3912 3337);
PAINT MONO (3912 3337);
FORCEPROP 1 LASTPIN (4100 3325) $PN 2
J 0
(4062 3337);
DISPLAY 0.787234 (4062 3337);
PAINT MONO (4062 3337);
FORCEPROP 1 LAST MATERIAL EMPTY
J 0
(4225 3325);
DISPLAY 0.510638 (4225 3325);
PAINT RED (4225 3325);
FORCEPROP 1 LAST VALUE 0
J 2
(4125 3325);
DISPLAY 0.510638 (4125 3325);
FORCEPROP 1 LAST TOLERANCE 5%
J 0
(4150 3325);
DISPLAY 0.510638 (4150 3325);
FORCEPROP 1 LAST PACK_TYPE 0402LF
J 0
(3900 3425);
DISPLAY 0.510638 (3900 3425);
FORCEPROP 1 LAST WATTAGE 1/16W
J 2
(4250 3425);
DISPLAY 0.510638 (4250 3425);
FORCEPROP 2 LAST CDS_LIB pure_quanta
J 0
(4000 3325);
DISPLAY INVISIBLE (4000 3325);
FORCEPROP 1 LAST PATH I103
J 0
(3950 3475);
DISPLAY 0.978723 (3950 3475);
PAINT WHITE (3950 3475);
DISPLAY INVISIBLE (3950 3475);
FORCEPROP 1 LAST PART_NUMBER CS00002JB13
J 0
(3950 3375);
DISPLAY 0.510638 (3950 3375);
DISPLAY INVISIBLE (3950 3375);
FORCEADD Q_RES..2
(175 4150);
FORCEPROP 1 LAST LOCATION R4128
J 0
(220 4275);
DISPLAY 0.638298 (220 4275);
FORCEPROP 2 LAST $SEC 1
J 0
(225 4375);
DISPLAY 0.680851 (225 4375);
PAINT MONO (225 4375);
DISPLAY INVISIBLE (225 4375);
FORCEPROP 2 LAST CDS_SEC 1
J 0
(225 4375);
DISPLAY 1.021277 (225 4375);
DISPLAY INVISIBLE (225 4375);
FORCEPROP 1 LASTPIN (175 4250) $PN 1
J 0
(180 4212);
DISPLAY 0.787234 (180 4212);
FORCEPROP 1 LASTPIN (175 4050) $PN 2
J 0
(180 4060);
DISPLAY 0.787234 (180 4060);
FORCEPROP 1 LAST VALUE 100K
J 0
(220 4225);
DISPLAY 0.638298 (220 4225);
FORCEPROP 1 LAST PACK_TYPE 0402LF
J 0
(215 4025);
DISPLAY 0.638298 (215 4025);
FORCEPROP 1 LAST MATERIAL CHIP
J 0
(215 4075);
DISPLAY 0.638298 (215 4075);
FORCEPROP 1 LAST WATTAGE 1/16W
J 0
(215 4125);
DISPLAY 0.638298 (215 4125);
FORCEPROP 1 LAST TOLERANCE 1%
J 0
(220 4175);
DISPLAY 0.638298 (220 4175);
FORCEPROP 2 LAST CDS_LIB pure_quanta
J 0
(175 4150);
PAINT MONO (175 4150);
DISPLAY INVISIBLE (175 4150);
FORCEPROP 1 LAST PATH I104
J 0
(225 4325);
DISPLAY 0.978723 (225 4325);
PAINT WHITE (225 4325);
DISPLAY INVISIBLE (225 4325);
FORCEPROP 1 LAST PART_NUMBER CS41002FB09
J 0
(215 3975);
DISPLAY 0.638298 (215 3975);
DISPLAY INVISIBLE (215 3975);
FORCEADD UNIVERSAL_POWER..1
(175 4375);
FORCEPROP 3 LASTPIN (175 4325) SIG_NAME P3V3_AUX\g
J 0
(185 4335);
DISPLAY 0.659574 (185 4335);
PAINT MONO (185 4335);
DISPLAY INVISIBLE (185 4335);
FORCEPROP 1 LAST HDL_POWER P3V3_AUX
J 1
(175 4425);
DISPLAY 0.872340 (175 4425);
PAINT GREEN (175 4425);
FORCEPROP 2 LAST CDS_LIB pure_quanta_power
J 0
(175 4375);
PAINT MONO (175 4375);
DISPLAY INVISIBLE (175 4375);
FORCEPROP 1 LAST PATH I105
J 0
(225 4400);
DISPLAY 0.872340 (225 4400);
PAINT AQUA (225 4400);
DISPLAY INVISIBLE (225 4400);
FORCEADD UNIVERSAL_POWER..1
(2475 4200);
FORCEPROP 3 LASTPIN (2475 4150) SIG_NAME P3V3_AUX\g
J 0
(2485 4160);
DISPLAY 0.659574 (2485 4160);
PAINT MONO (2485 4160);
DISPLAY INVISIBLE (2485 4160);
FORCEPROP 1 LAST HDL_POWER P3V3_AUX
J 1
(2475 4250);
DISPLAY 0.872340 (2475 4250);
PAINT GREEN (2475 4250);
FORCEPROP 2 LAST CDS_LIB pure_quanta_power
J 0
(2475 4200);
PAINT MONO (2475 4200);
DISPLAY INVISIBLE (2475 4200);
FORCEPROP 1 LAST PATH I106
J 0
(2525 4225);
DISPLAY 0.872340 (2525 4225);
PAINT AQUA (2525 4225);
DISPLAY INVISIBLE (2525 4225);
FORCEADD Q_RES..2
(3650 4325);
FORCEPROP 1 LAST LOCATION R4137
J 0
(3695 4450);
DISPLAY 0.638298 (3695 4450);
FORCEPROP 2 LAST $SEC 1
J 0
(3700 4550);
DISPLAY 0.680851 (3700 4550);
PAINT MONO (3700 4550);
DISPLAY INVISIBLE (3700 4550);
FORCEPROP 2 LAST CDS_SEC 1
J 0
(3700 4550);
DISPLAY 1.021277 (3700 4550);
DISPLAY INVISIBLE (3700 4550);
FORCEPROP 1 LASTPIN (3650 4425) $PN 1
J 0
(3655 4387);
DISPLAY 0.787234 (3655 4387);
FORCEPROP 1 LASTPIN (3650 4225) $PN 2
J 0
(3655 4235);
DISPLAY 0.787234 (3655 4235);
FORCEPROP 1 LAST TOLERANCE 5%
J 0
(3695 4350);
DISPLAY 0.638298 (3695 4350);
FORCEPROP 1 LAST VALUE 4.7K
J 0
(3695 4400);
DISPLAY 0.638298 (3695 4400);
FORCEPROP 1 LAST WATTAGE 1/16W
J 0
(3690 4300);
DISPLAY 0.638298 (3690 4300);
FORCEPROP 1 LAST PACK_TYPE 0402LF
J 0
(3690 4200);
DISPLAY 0.638298 (3690 4200);
FORCEPROP 1 LAST MATERIAL CHIP
J 0
(3690 4250);
DISPLAY 0.638298 (3690 4250);
FORCEPROP 2 LAST CDS_LIB pure_quanta
J 0
(3650 4325);
PAINT MONO (3650 4325);
DISPLAY INVISIBLE (3650 4325);
FORCEPROP 1 LAST PATH I107
J 0
(3700 4500);
DISPLAY 0.978723 (3700 4500);
PAINT WHITE (3700 4500);
DISPLAY INVISIBLE (3700 4500);
FORCEPROP 1 LAST PART_NUMBER CS24702JB10
J 0
(3690 4150);
DISPLAY 0.638298 (3690 4150);
DISPLAY INVISIBLE (3690 4150);
FORCEADD UNIVERSAL_POWER..1
(3650 4550);
FORCEPROP 3 LASTPIN (3650 4500) SIG_NAME P3V3_AUX\g
J 0
(3660 4510);
DISPLAY 0.659574 (3660 4510);
PAINT MONO (3660 4510);
DISPLAY INVISIBLE (3660 4510);
FORCEPROP 1 LAST HDL_POWER P3V3_AUX
J 1
(3650 4600);
DISPLAY 0.872340 (3650 4600);
PAINT GREEN (3650 4600);
FORCEPROP 2 LAST CDS_LIB pure_quanta_power
J 0
(3650 4550);
PAINT MONO (3650 4550);
DISPLAY INVISIBLE (3650 4550);
FORCEPROP 1 LAST PATH I108
J 0
(3700 4575);
DISPLAY 0.872340 (3700 4575);
PAINT AQUA (3700 4575);
DISPLAY INVISIBLE (3700 4575);
FORCEADD Q_RES..1
(3950 4700);
FORCEPROP 1 LAST LOCATION R4577
J 0
(3700 4700);
DISPLAY 0.787234 (3700 4700);
FORCEPROP 0 LAST $SEC 1
J 0
(4200 4825);
DISPLAY 0.680851 (4200 4825);
PAINT MONO (4200 4825);
DISPLAY INVISIBLE (4200 4825);
FORCEPROP 0 LAST CDS_SEC 1
J 0
(4200 4825);
DISPLAY 1.021277 (4200 4825);
DISPLAY INVISIBLE (4200 4825);
FORCEPROP 1 LASTPIN (3850 4700) $PN 1
J 0
(3862 4712);
DISPLAY 0.787234 (3862 4712);
PAINT MONO (3862 4712);
FORCEPROP 1 LASTPIN (4050 4700) $PN 2
J 0
(4012 4712);
DISPLAY 0.787234 (4012 4712);
PAINT MONO (4012 4712);
FORCEPROP 1 LAST PACK_TYPE 0402LF
J 0
(3850 4800);
DISPLAY 0.510638 (3850 4800);
FORCEPROP 1 LAST WATTAGE 1/16W
J 2
(4200 4800);
DISPLAY 0.510638 (4200 4800);
FORCEPROP 1 LAST MATERIAL EMPTY
J 0
(4175 4700);
DISPLAY 0.510638 (4175 4700);
PAINT RED (4175 4700);
FORCEPROP 1 LAST VALUE 0
J 2
(4075 4700);
DISPLAY 0.510638 (4075 4700);
FORCEPROP 1 LAST TOLERANCE 5%
J 0
(4100 4700);
DISPLAY 0.510638 (4100 4700);
FORCEPROP 2 LAST CDS_LIB pure_quanta
J 0
(3950 4700);
DISPLAY INVISIBLE (3950 4700);
FORCEPROP 1 LAST PATH I109
J 0
(3900 4850);
DISPLAY 0.978723 (3900 4850);
PAINT WHITE (3900 4850);
DISPLAY INVISIBLE (3900 4850);
FORCEPROP 1 LAST PART_NUMBER CS00002JB13
J 0
(3900 4750);
DISPLAY 0.510638 (3900 4750);
DISPLAY INVISIBLE (3900 4750);
FORCEADD OFFPAGE..4
R 2
(-2400 550);
FORCEPROP 2 LAST $XR0 119 
J 0
(-2652 550);
DISPLAY 0.638298 (-2652 550);
PAINT MONO (-2652 550);
FORCEPROP 2 LAST CDS_LIB standard
J 0
(-2400 550);
DISPLAY INVISIBLE (-2400 550);
FORCEPROP 1 LAST OFFPAGE TRUE
J 2
(-2725 425);
DISPLAY 0.872340 (-2725 425);
PAINT GREEN (-2725 425);
DISPLAY INVISIBLE (-2725 425);
FORCEPROP 1 LAST COMMENT_BODY TRUE
J 2
(-2375 450);
DISPLAY 0.872340 (-2375 450);
PAINT GREEN (-2375 450);
DISPLAY INVISIBLE (-2375 450);
FORCEPROP 2 LAST PATH I11
J 0
(-2675 600);
DISPLAY 0.680851 (-2675 600);
DISPLAY INVISIBLE (-2675 600);
FORCEADD Q_RES..2
(4800 150);
FORCEPROP 1 LAST LOCATION R4561
J 0
(4845 275);
DISPLAY 0.638298 (4845 275);
FORCEPROP 2 LAST $SEC 1
J 0
(4850 375);
DISPLAY 0.680851 (4850 375);
PAINT MONO (4850 375);
DISPLAY INVISIBLE (4850 375);
FORCEPROP 2 LAST CDS_SEC 1
J 0
(4850 375);
DISPLAY 1.021277 (4850 375);
DISPLAY INVISIBLE (4850 375);
FORCEPROP 1 LASTPIN (4800 250) $PN 1
J 0
(4805 212);
DISPLAY 0.787234 (4805 212);
FORCEPROP 1 LASTPIN (4800 50) $PN 2
J 0
(4805 60);
DISPLAY 0.787234 (4805 60);
FORCEPROP 1 LAST TOLERANCE 1%
J 0
(4845 175);
DISPLAY 0.638298 (4845 175);
FORCEPROP 1 LAST VALUE 100K
J 0
(4845 225);
DISPLAY 0.638298 (4845 225);
FORCEPROP 1 LAST WATTAGE 1/16W
J 0
(4840 125);
DISPLAY 0.638298 (4840 125);
FORCEPROP 1 LAST MATERIAL CHIP
J 0
(4840 75);
DISPLAY 0.638298 (4840 75);
FORCEPROP 1 LAST PACK_TYPE 0402LF
J 0
(4840 25);
DISPLAY 0.638298 (4840 25);
FORCEPROP 2 LAST CDS_LIB pure_quanta
J 0
(4800 150);
PAINT MONO (4800 150);
DISPLAY INVISIBLE (4800 150);
FORCEPROP 1 LAST PATH I110
J 0
(4850 325);
DISPLAY 0.978723 (4850 325);
PAINT WHITE (4850 325);
DISPLAY INVISIBLE (4850 325);
FORCEPROP 1 LAST PART_NUMBER CS41002FB09
J 0
(4840 -25);
DISPLAY 0.638298 (4840 -25);
DISPLAY INVISIBLE (4840 -25);
FORCEADD UNIVERSAL_POWER..1
(4800 375);
FORCEPROP 3 LASTPIN (4800 325) SIG_NAME P3V3_AUX\g
J 0
(4810 335);
DISPLAY 0.659574 (4810 335);
PAINT MONO (4810 335);
DISPLAY INVISIBLE (4810 335);
FORCEPROP 1 LAST HDL_POWER P3V3_AUX
J 1
(4800 425);
DISPLAY 0.872340 (4800 425);
PAINT GREEN (4800 425);
FORCEPROP 2 LAST CDS_LIB pure_quanta_power
J 0
(4800 375);
PAINT MONO (4800 375);
DISPLAY INVISIBLE (4800 375);
FORCEPROP 1 LAST PATH I111
J 0
(4850 400);
DISPLAY 0.872340 (4850 400);
PAINT AQUA (4850 400);
DISPLAY INVISIBLE (4850 400);
FORCEADD UNIVERSAL_GND..1
(4800 825);
FORCEPROP 3 LASTPIN (4800 875) SIG_NAME GND\g
J 0
(4810 885);
DISPLAY 0.659574 (4810 885);
PAINT MONO (4810 885);
DISPLAY INVISIBLE (4810 885);
FORCEPROP 2 LAST CDS_LIB pure_quanta_power
J 0
(4800 825);
DISPLAY INVISIBLE (4800 825);
FORCEPROP 1 LAST HDL_POWER GND
J 1
(4825 750);
DISPLAY 0.872340 (4825 750);
PAINT GREEN (4825 750);
DISPLAY INVISIBLE (4825 750);
FORCEPROP 1 LAST PATH I112
J 0
(4875 825);
DISPLAY 0.872340 (4875 825);
PAINT AQUA (4875 825);
DISPLAY INVISIBLE (4875 825);
FORCEADD MOSFET_NCH_DUAL..2
(4750 1200);
FORCEPROP 1 LAST LOCATION Q129
J 0
(4901 1176);
DISPLAY 0.723404 (4901 1176);
PAINT GREEN (4901 1176);
FORCEPROP 0 LAST $SEC 2
J 0
(4925 1325);
DISPLAY 0.680851 (4925 1325);
PAINT MONO (4925 1325);
DISPLAY INVISIBLE (4925 1325);
FORCEPROP 0 LAST CDS_SEC 2
J 0
(4925 1325);
DISPLAY 1.021277 (4925 1325);
DISPLAY INVISIBLE (4925 1325);
FORCEPROP 0 LASTPIN (4800 1400) $PN 3
R 1
J 0
(4790 1410);
DISPLAY 0.680851 (4790 1410);
PAINT MONO (4790 1410);
FORCEPROP 0 LASTPIN (4550 1150) $PN 5
J 2
(4540 1160);
DISPLAY 0.680851 (4540 1160);
PAINT MONO (4540 1160);
FORCEPROP 0 LASTPIN (4800 1000) $PN 4
R 1
J 2
(4790 990);
DISPLAY 0.680851 (4790 990);
PAINT MONO (4790 990);
FORCEPROP 2 LAST PART_TYPE SMLF
J 0
(4925 1275);
DISPLAY 1.021277 (4925 1275);
FORCEPROP 2 LAST VALUE PJT138K
J 0
(4925 1225);
DISPLAY 1.021277 (4925 1225);
FORCEPROP 1 LAST MATERIAL IC
J 0
(4901 1051);
DISPLAY 0.723404 (4901 1051);
PAINT GREEN (4901 1051);
FORCEPROP 1 LAST CDS_LMAN_SYM_OUTLINE -150,150,150,-150
J 0
(4750 1200);
DISPLAY 0.468085 (4750 1200);
PAINT GREEN (4750 1200);
DISPLAY INVISIBLE (4750 1200);
FORCEPROP 1 LAST NEEDS_NO_SIZE TRUE
J 0
(4900 1091);
DISPLAY 0.468085 (4900 1091);
PAINT GREEN (4900 1091);
DISPLAY INVISIBLE (4900 1091);
FORCEPROP 2 LAST CDS_LIB pure_quanta
J 0
(4750 1200);
DISPLAY INVISIBLE (4750 1200);
FORCEPROP 1 LAST PATH I113
J 0
(4900 1050);
DISPLAY 0.723404 (4900 1050);
PAINT GREEN (4900 1050);
DISPLAY INVISIBLE (4900 1050);
FORCEPROP 1 LAST PART_NUMBER BAM138K0003
J 0
(4901 1106);
DISPLAY 0.723404 (4901 1106);
PAINT GREEN (4901 1106);
DISPLAY INVISIBLE (4901 1106);
FORCEADD Q_RES..2
(4800 1625);
FORCEPROP 1 LAST LOCATION R4141
J 0
(4845 1750);
DISPLAY 0.638298 (4845 1750);
FORCEPROP 2 LAST $SEC 1
J 0
(4850 1850);
DISPLAY 0.680851 (4850 1850);
PAINT MONO (4850 1850);
DISPLAY INVISIBLE (4850 1850);
FORCEPROP 2 LAST CDS_SEC 1
J 0
(4850 1850);
DISPLAY 1.021277 (4850 1850);
DISPLAY INVISIBLE (4850 1850);
FORCEPROP 1 LASTPIN (4800 1725) $PN 1
J 0
(4805 1687);
DISPLAY 0.787234 (4805 1687);
FORCEPROP 1 LASTPIN (4800 1525) $PN 2
J 0
(4805 1535);
DISPLAY 0.787234 (4805 1535);
FORCEPROP 1 LAST TOLERANCE 1%
J 0
(4845 1650);
DISPLAY 0.638298 (4845 1650);
FORCEPROP 1 LAST VALUE 100K
J 0
(4845 1700);
DISPLAY 0.638298 (4845 1700);
FORCEPROP 1 LAST MATERIAL CHIP
J 0
(4840 1550);
DISPLAY 0.638298 (4840 1550);
FORCEPROP 1 LAST WATTAGE 1/16W
J 0
(4840 1600);
DISPLAY 0.638298 (4840 1600);
FORCEPROP 1 LAST PACK_TYPE 0402LF
J 0
(4840 1500);
DISPLAY 0.638298 (4840 1500);
FORCEPROP 2 LAST CDS_LIB pure_quanta
J 0
(4800 1625);
PAINT MONO (4800 1625);
DISPLAY INVISIBLE (4800 1625);
FORCEPROP 1 LAST PATH I114
J 0
(4850 1800);
DISPLAY 0.978723 (4850 1800);
PAINT WHITE (4850 1800);
DISPLAY INVISIBLE (4850 1800);
FORCEPROP 1 LAST PART_NUMBER CS41002FB09
J 0
(4840 1450);
DISPLAY 0.638298 (4840 1450);
DISPLAY INVISIBLE (4840 1450);
FORCEADD UNIVERSAL_POWER..1
(4800 1850);
FORCEPROP 3 LASTPIN (4800 1800) SIG_NAME P3V3_AUX\g
J 0
(4810 1810);
DISPLAY 0.659574 (4810 1810);
PAINT MONO (4810 1810);
DISPLAY INVISIBLE (4810 1810);
FORCEPROP 1 LAST HDL_POWER P3V3_AUX
J 1
(4800 1900);
DISPLAY 0.872340 (4800 1900);
PAINT GREEN (4800 1900);
FORCEPROP 2 LAST CDS_LIB pure_quanta_power
J 0
(4800 1850);
PAINT MONO (4800 1850);
DISPLAY INVISIBLE (4800 1850);
FORCEPROP 1 LAST PATH I115
J 0
(4850 1875);
DISPLAY 0.872340 (4850 1875);
PAINT AQUA (4850 1875);
DISPLAY INVISIBLE (4850 1875);
FORCEADD UNIVERSAL_GND..1
(5575 950);
FORCEPROP 3 LASTPIN (5575 1000) SIG_NAME GND\g
J 0
(5585 1010);
DISPLAY 0.659574 (5585 1010);
PAINT MONO (5585 1010);
DISPLAY INVISIBLE (5585 1010);
FORCEPROP 2 LAST CDS_LIB pure_quanta_power
J 0
(5575 950);
DISPLAY INVISIBLE (5575 950);
FORCEPROP 1 LAST HDL_POWER GND
J 1
(5600 875);
DISPLAY 0.872340 (5600 875);
PAINT GREEN (5600 875);
DISPLAY INVISIBLE (5600 875);
FORCEPROP 1 LAST PATH I116
J 0
(5650 950);
DISPLAY 0.872340 (5650 950);
PAINT AQUA (5650 950);
DISPLAY INVISIBLE (5650 950);
FORCEADD OFFPAGE..2
(5925 -25);
FORCEPROP 2 LAST $XR0 81 
J 0
(6114 -25);
DISPLAY 0.638298 (6114 -25);
PAINT MONO (6114 -25);
FORCEPROP 2 LAST CDS_LIB standard
J 0
(5925 -25);
DISPLAY INVISIBLE (5925 -25);
FORCEPROP 1 LAST OFFPAGE TRUE
J 0
(6250 -150);
DISPLAY 0.872340 (6250 -150);
PAINT AQUA (6250 -150);
DISPLAY INVISIBLE (6250 -150);
FORCEPROP 1 LAST COMMENT_BODY TRUE
J 0
(5880 -120);
DISPLAY 0.872340 (5880 -120);
PAINT GREEN (5880 -120);
DISPLAY INVISIBLE (5880 -120);
FORCEPROP 2 LAST PATH I117
J 0
(6125 25);
DISPLAY 0.680851 (6125 25);
DISPLAY INVISIBLE (6125 25);
FORCEADD Q_CAP..1
(5575 1150);
FORCEPROP 1 LAST LOCATION C17
J 0
(5625 1250);
DISPLAY 0.978723 (5625 1250);
FORCEPROP 0 LAST $SEC 1
J 0
(5625 1300);
DISPLAY 0.680851 (5625 1300);
PAINT MONO (5625 1300);
DISPLAY INVISIBLE (5625 1300);
FORCEPROP 0 LAST CDS_SEC 1
J 0
(5625 1300);
DISPLAY 1.021277 (5625 1300);
DISPLAY INVISIBLE (5625 1300);
FORCEPROP 1 LASTPIN (5575 1250) $PN 1
J 0
(5585 1230);
DISPLAY 0.787234 (5585 1230);
PAINT MONO (5585 1230);
FORCEPROP 1 LASTPIN (5575 1050) $PN 2
J 0
(5585 1030);
DISPLAY 0.787234 (5585 1030);
PAINT MONO (5585 1030);
FORCEPROP 1 LAST VOLTAGE 25V
J 0
(5625 1150);
DISPLAY 0.638298 (5625 1150);
FORCEPROP 1 LAST TOLERANCE 10%
J 0
(5625 1100);
DISPLAY 0.638298 (5625 1100);
FORCEPROP 1 LAST PACK_TYPE 0402
J 0
(5625 950);
DISPLAY 0.638298 (5625 950);
FORCEPROP 1 LAST MATERIAL X7R
J 0
(5625 1050);
DISPLAY 0.638298 (5625 1050);
PAINT RED (5625 1050);
FORCEPROP 1 LAST VALUE 0.1UF
J 0
(5625 1200);
DISPLAY 0.638298 (5625 1200);
FORCEPROP 2 LAST CDS_LIB pure_quanta
J 0
(5575 1150);
DISPLAY INVISIBLE (5575 1150);
FORCEPROP 1 LAST PATH I118
J 0
(5625 1300);
DISPLAY 0.978723 (5625 1300);
PAINT WHITE (5625 1300);
DISPLAY INVISIBLE (5625 1300);
FORCEPROP 1 LAST PART_NUMBER CH4104K1B00
J 0
(5625 1000);
DISPLAY 0.638298 (5625 1000);
DISPLAY INVISIBLE (5625 1000);
FORCEADD OFFPAGE..2
(5925 1450);
FORCEPROP 2 LAST $XR0 81 
J 0
(6114 1450);
DISPLAY 0.638298 (6114 1450);
PAINT MONO (6114 1450);
FORCEPROP 2 LAST CDS_LIB standard
J 0
(5925 1450);
DISPLAY INVISIBLE (5925 1450);
FORCEPROP 1 LAST OFFPAGE TRUE
J 0
(6250 1325);
DISPLAY 0.872340 (6250 1325);
PAINT AQUA (6250 1325);
DISPLAY INVISIBLE (6250 1325);
FORCEPROP 1 LAST COMMENT_BODY TRUE
J 0
(5880 1355);
DISPLAY 0.872340 (5880 1355);
PAINT GREEN (5880 1355);
DISPLAY INVISIBLE (5880 1355);
FORCEPROP 2 LAST PATH I119
J 0
(6125 1500);
DISPLAY 0.680851 (6125 1500);
DISPLAY INVISIBLE (6125 1500);
FORCEADD UNIVERSAL_GND..1
(-2125 75);
FORCEPROP 3 LASTPIN (-2125 125) SIG_NAME GND\g
J 0
(-2115 135);
DISPLAY 0.659574 (-2115 135);
PAINT MONO (-2115 135);
DISPLAY INVISIBLE (-2115 135);
FORCEPROP 2 LAST CDS_LIB pure_quanta_power
J 0
(-2125 75);
DISPLAY INVISIBLE (-2125 75);
FORCEPROP 1 LAST HDL_POWER GND
J 1
(-2100 0);
DISPLAY 0.872340 (-2100 0);
PAINT GREEN (-2100 0);
DISPLAY INVISIBLE (-2100 0);
FORCEPROP 1 LAST PATH I12
J 0
(-2050 75);
DISPLAY 0.872340 (-2050 75);
PAINT AQUA (-2050 75);
DISPLAY INVISIBLE (-2050 75);
FORCEADD MOSFET_NCH_DUAL..2
(4775 2650);
FORCEPROP 1 LAST LOCATION Q133
J 0
(4926 2626);
DISPLAY 0.723404 (4926 2626);
PAINT GREEN (4926 2626);
FORCEPROP 0 LAST $SEC 2
J 0
(4950 2775);
DISPLAY 0.680851 (4950 2775);
PAINT MONO (4950 2775);
DISPLAY INVISIBLE (4950 2775);
FORCEPROP 0 LAST CDS_SEC 2
J 0
(4950 2775);
DISPLAY 1.021277 (4950 2775);
DISPLAY INVISIBLE (4950 2775);
FORCEPROP 0 LASTPIN (4825 2850) $PN 3
R 1
J 0
(4815 2860);
DISPLAY 0.680851 (4815 2860);
PAINT MONO (4815 2860);
FORCEPROP 0 LASTPIN (4575 2600) $PN 5
J 2
(4565 2610);
DISPLAY 0.680851 (4565 2610);
PAINT MONO (4565 2610);
FORCEPROP 0 LASTPIN (4825 2450) $PN 4
R 1
J 2
(4815 2440);
DISPLAY 0.680851 (4815 2440);
PAINT MONO (4815 2440);
FORCEPROP 2 LAST VALUE PJT138K
J 0
(4950 2675);
DISPLAY 1.021277 (4950 2675);
FORCEPROP 2 LAST PART_TYPE SMLF
J 0
(4950 2725);
DISPLAY 1.021277 (4950 2725);
FORCEPROP 1 LAST MATERIAL IC
J 0
(4926 2501);
DISPLAY 0.723404 (4926 2501);
PAINT GREEN (4926 2501);
FORCEPROP 1 LAST CDS_LMAN_SYM_OUTLINE -150,150,150,-150
J 0
(4775 2650);
DISPLAY 0.468085 (4775 2650);
PAINT GREEN (4775 2650);
DISPLAY INVISIBLE (4775 2650);
FORCEPROP 1 LAST NEEDS_NO_SIZE TRUE
J 0
(4925 2541);
DISPLAY 0.468085 (4925 2541);
PAINT GREEN (4925 2541);
DISPLAY INVISIBLE (4925 2541);
FORCEPROP 2 LAST CDS_LIB pure_quanta
J 0
(4775 2650);
DISPLAY INVISIBLE (4775 2650);
FORCEPROP 1 LAST PATH I120
J 0
(4925 2500);
DISPLAY 0.723404 (4925 2500);
PAINT GREEN (4925 2500);
DISPLAY INVISIBLE (4925 2500);
FORCEPROP 1 LAST PART_NUMBER BAM138K0003
J 0
(4926 2556);
DISPLAY 0.723404 (4926 2556);
PAINT GREEN (4926 2556);
DISPLAY INVISIBLE (4926 2556);
FORCEADD UNIVERSAL_GND..1
(4825 2275);
FORCEPROP 3 LASTPIN (4825 2325) SIG_NAME GND\g
J 0
(4835 2335);
DISPLAY 0.659574 (4835 2335);
PAINT MONO (4835 2335);
DISPLAY INVISIBLE (4835 2335);
FORCEPROP 2 LAST CDS_LIB pure_quanta_power
J 0
(4825 2275);
DISPLAY INVISIBLE (4825 2275);
FORCEPROP 1 LAST HDL_POWER GND
J 1
(4850 2200);
DISPLAY 0.872340 (4850 2200);
PAINT GREEN (4850 2200);
DISPLAY INVISIBLE (4850 2200);
FORCEPROP 1 LAST PATH I121
J 0
(4900 2275);
DISPLAY 0.872340 (4900 2275);
PAINT AQUA (4900 2275);
DISPLAY INVISIBLE (4900 2275);
FORCEADD Q_RES..2
(4825 3075);
FORCEPROP 1 LAST LOCATION R4142
J 0
(4870 3200);
DISPLAY 0.638298 (4870 3200);
FORCEPROP 2 LAST $SEC 1
J 0
(4875 3300);
DISPLAY 0.680851 (4875 3300);
PAINT MONO (4875 3300);
DISPLAY INVISIBLE (4875 3300);
FORCEPROP 2 LAST CDS_SEC 1
J 0
(4875 3300);
DISPLAY 1.021277 (4875 3300);
DISPLAY INVISIBLE (4875 3300);
FORCEPROP 1 LASTPIN (4825 3175) $PN 1
J 0
(4830 3137);
DISPLAY 0.787234 (4830 3137);
FORCEPROP 1 LASTPIN (4825 2975) $PN 2
J 0
(4830 2985);
DISPLAY 0.787234 (4830 2985);
FORCEPROP 1 LAST TOLERANCE 1%
J 0
(4870 3100);
DISPLAY 0.638298 (4870 3100);
FORCEPROP 1 LAST VALUE 100K
J 0
(4870 3150);
DISPLAY 0.638298 (4870 3150);
FORCEPROP 1 LAST WATTAGE 1/16W
J 0
(4865 3050);
DISPLAY 0.638298 (4865 3050);
FORCEPROP 1 LAST MATERIAL CHIP
J 0
(4865 3000);
DISPLAY 0.638298 (4865 3000);
FORCEPROP 1 LAST PACK_TYPE 0402LF
J 0
(4865 2950);
DISPLAY 0.638298 (4865 2950);
FORCEPROP 2 LAST CDS_LIB pure_quanta
J 0
(4825 3075);
PAINT MONO (4825 3075);
DISPLAY INVISIBLE (4825 3075);
FORCEPROP 1 LAST PATH I122
J 0
(4875 3250);
DISPLAY 0.978723 (4875 3250);
PAINT WHITE (4875 3250);
DISPLAY INVISIBLE (4875 3250);
FORCEPROP 1 LAST PART_NUMBER CS41002FB09
J 0
(4865 2900);
DISPLAY 0.638298 (4865 2900);
DISPLAY INVISIBLE (4865 2900);
FORCEADD MOSFET_NCH_DUAL..2
(4750 4025);
FORCEPROP 1 LAST LOCATION Q130
J 0
(4901 4001);
DISPLAY 0.723404 (4901 4001);
PAINT GREEN (4901 4001);
FORCEPROP 0 LAST $SEC 2
J 0
(4925 4150);
DISPLAY 0.680851 (4925 4150);
PAINT MONO (4925 4150);
DISPLAY INVISIBLE (4925 4150);
FORCEPROP 0 LAST CDS_SEC 2
J 0
(4925 4150);
DISPLAY 1.021277 (4925 4150);
DISPLAY INVISIBLE (4925 4150);
FORCEPROP 0 LASTPIN (4800 4225) $PN 3
R 1
J 0
(4790 4235);
DISPLAY 0.680851 (4790 4235);
PAINT MONO (4790 4235);
FORCEPROP 0 LASTPIN (4550 3975) $PN 5
J 2
(4540 3985);
DISPLAY 0.680851 (4540 3985);
PAINT MONO (4540 3985);
FORCEPROP 0 LASTPIN (4800 3825) $PN 4
R 1
J 2
(4790 3815);
DISPLAY 0.680851 (4790 3815);
PAINT MONO (4790 3815);
FORCEPROP 1 LAST MATERIAL IC
J 0
(4901 3876);
DISPLAY 0.723404 (4901 3876);
PAINT GREEN (4901 3876);
FORCEPROP 2 LAST VALUE PJT138K
J 0
(4925 4050);
DISPLAY 1.021277 (4925 4050);
FORCEPROP 2 LAST PART_TYPE SMLF
J 0
(4925 4100);
DISPLAY 1.021277 (4925 4100);
FORCEPROP 1 LAST CDS_LMAN_SYM_OUTLINE -150,150,150,-150
J 0
(4750 4025);
DISPLAY 0.468085 (4750 4025);
PAINT GREEN (4750 4025);
DISPLAY INVISIBLE (4750 4025);
FORCEPROP 1 LAST NEEDS_NO_SIZE TRUE
J 0
(4900 3916);
DISPLAY 0.468085 (4900 3916);
PAINT GREEN (4900 3916);
DISPLAY INVISIBLE (4900 3916);
FORCEPROP 2 LAST CDS_LIB pure_quanta
J 0
(4750 4025);
DISPLAY INVISIBLE (4750 4025);
FORCEPROP 1 LAST PATH I123
J 0
(4900 3875);
DISPLAY 0.723404 (4900 3875);
PAINT GREEN (4900 3875);
DISPLAY INVISIBLE (4900 3875);
FORCEPROP 1 LAST PART_NUMBER BAM138K0003
J 0
(4901 3931);
DISPLAY 0.723404 (4901 3931);
PAINT GREEN (4901 3931);
DISPLAY INVISIBLE (4901 3931);
FORCEADD UNIVERSAL_POWER..1
(4825 3300);
FORCEPROP 3 LASTPIN (4825 3250) SIG_NAME P3V3_AUX\g
J 0
(4835 3260);
DISPLAY 0.659574 (4835 3260);
PAINT MONO (4835 3260);
DISPLAY INVISIBLE (4835 3260);
FORCEPROP 1 LAST HDL_POWER P3V3_AUX
J 1
(4825 3350);
DISPLAY 0.872340 (4825 3350);
PAINT GREEN (4825 3350);
FORCEPROP 2 LAST CDS_LIB pure_quanta_power
J 0
(4825 3300);
PAINT MONO (4825 3300);
DISPLAY INVISIBLE (4825 3300);
FORCEPROP 1 LAST PATH I124
J 0
(4875 3325);
DISPLAY 0.872340 (4875 3325);
PAINT AQUA (4875 3325);
DISPLAY INVISIBLE (4875 3325);
FORCEADD UNIVERSAL_GND..1
(4800 3650);
FORCEPROP 3 LASTPIN (4800 3700) SIG_NAME GND\g
J 0
(4810 3710);
DISPLAY 0.659574 (4810 3710);
PAINT MONO (4810 3710);
DISPLAY INVISIBLE (4810 3710);
FORCEPROP 2 LAST CDS_LIB pure_quanta_power
J 0
(4800 3650);
DISPLAY INVISIBLE (4800 3650);
FORCEPROP 1 LAST HDL_POWER GND
J 1
(4825 3575);
DISPLAY 0.872340 (4825 3575);
PAINT GREEN (4825 3575);
DISPLAY INVISIBLE (4825 3575);
FORCEPROP 1 LAST PATH I125
J 0
(4875 3650);
DISPLAY 0.872340 (4875 3650);
PAINT AQUA (4875 3650);
DISPLAY INVISIBLE (4875 3650);
FORCEADD UNIVERSAL_GND..1
(5600 2400);
FORCEPROP 3 LASTPIN (5600 2450) SIG_NAME GND\g
J 0
(5610 2460);
DISPLAY 0.659574 (5610 2460);
PAINT MONO (5610 2460);
DISPLAY INVISIBLE (5610 2460);
FORCEPROP 2 LAST CDS_LIB pure_quanta_power
J 0
(5600 2400);
DISPLAY INVISIBLE (5600 2400);
FORCEPROP 1 LAST HDL_POWER GND
J 1
(5625 2325);
DISPLAY 0.872340 (5625 2325);
PAINT GREEN (5625 2325);
DISPLAY INVISIBLE (5625 2325);
FORCEPROP 1 LAST PATH I126
J 0
(5675 2400);
DISPLAY 0.872340 (5675 2400);
PAINT AQUA (5675 2400);
DISPLAY INVISIBLE (5675 2400);
FORCEADD Q_CAP..1
(5600 2600);
FORCEPROP 1 LAST LOCATION C19
J 0
(5650 2700);
DISPLAY 0.978723 (5650 2700);
FORCEPROP 0 LAST $SEC 1
J 0
(5650 2750);
DISPLAY 0.680851 (5650 2750);
PAINT MONO (5650 2750);
DISPLAY INVISIBLE (5650 2750);
FORCEPROP 0 LAST CDS_SEC 1
J 0
(5650 2750);
DISPLAY 1.021277 (5650 2750);
DISPLAY INVISIBLE (5650 2750);
FORCEPROP 1 LASTPIN (5600 2700) $PN 1
J 0
(5610 2680);
DISPLAY 0.787234 (5610 2680);
PAINT MONO (5610 2680);
FORCEPROP 1 LASTPIN (5600 2500) $PN 2
J 0
(5610 2480);
DISPLAY 0.787234 (5610 2480);
PAINT MONO (5610 2480);
FORCEPROP 1 LAST PACK_TYPE 0402
J 0
(5650 2400);
DISPLAY 0.638298 (5650 2400);
FORCEPROP 1 LAST TOLERANCE 10%
J 0
(5650 2550);
DISPLAY 0.638298 (5650 2550);
FORCEPROP 1 LAST VOLTAGE 25V
J 0
(5650 2600);
DISPLAY 0.638298 (5650 2600);
FORCEPROP 1 LAST VALUE 0.1UF
J 0
(5650 2650);
DISPLAY 0.638298 (5650 2650);
FORCEPROP 1 LAST MATERIAL X7R
J 0
(5650 2500);
DISPLAY 0.638298 (5650 2500);
PAINT RED (5650 2500);
FORCEPROP 2 LAST CDS_LIB pure_quanta
J 0
(5600 2600);
DISPLAY INVISIBLE (5600 2600);
FORCEPROP 1 LAST PATH I127
J 0
(5650 2750);
DISPLAY 0.978723 (5650 2750);
PAINT WHITE (5650 2750);
DISPLAY INVISIBLE (5650 2750);
FORCEPROP 1 LAST PART_NUMBER CH4104K1B00
J 0
(5650 2450);
DISPLAY 0.638298 (5650 2450);
DISPLAY INVISIBLE (5650 2450);
FORCEADD OFFPAGE..2
(5950 2900);
FORCEPROP 2 LAST $XR1 246 
J 0
(6229 2900);
DISPLAY 0.638298 (6229 2900);
PAINT MONO (6229 2900);
FORCEPROP 2 LAST $XR0 81 
J 0
(6139 2900);
DISPLAY 0.638298 (6139 2900);
PAINT MONO (6139 2900);
FORCEPROP 2 LAST CDS_LIB standard
J 0
(5950 2900);
DISPLAY INVISIBLE (5950 2900);
FORCEPROP 1 LAST OFFPAGE TRUE
J 0
(6275 2775);
DISPLAY 0.872340 (6275 2775);
PAINT AQUA (6275 2775);
DISPLAY INVISIBLE (6275 2775);
FORCEPROP 1 LAST COMMENT_BODY TRUE
J 0
(5905 2805);
DISPLAY 0.872340 (5905 2805);
PAINT GREEN (5905 2805);
DISPLAY INVISIBLE (5905 2805);
FORCEPROP 2 LAST PATH I128
J 0
(6250 2950);
DISPLAY 0.680851 (6250 2950);
DISPLAY INVISIBLE (6250 2950);
FORCEADD UNIVERSAL_GND..1
(5575 3775);
FORCEPROP 3 LASTPIN (5575 3825) SIG_NAME GND\g
J 0
(5585 3835);
DISPLAY 0.659574 (5585 3835);
PAINT MONO (5585 3835);
DISPLAY INVISIBLE (5585 3835);
FORCEPROP 2 LAST CDS_LIB pure_quanta_power
J 0
(5575 3775);
DISPLAY INVISIBLE (5575 3775);
FORCEPROP 1 LAST HDL_POWER GND
J 1
(5600 3700);
DISPLAY 0.872340 (5600 3700);
PAINT GREEN (5600 3700);
DISPLAY INVISIBLE (5600 3700);
FORCEPROP 1 LAST PATH I129
J 0
(5650 3775);
DISPLAY 0.872340 (5650 3775);
PAINT AQUA (5650 3775);
DISPLAY INVISIBLE (5650 3775);
FORCEADD Q_RES..2
(-2125 350);
FORCEPROP 1 LAST LOCATION R4122
J 0
(-2080 475);
DISPLAY 0.978723 (-2080 475);
FORCEPROP 0 LAST $SEC 1
J 0
(-2075 525);
DISPLAY 0.680851 (-2075 525);
PAINT MONO (-2075 525);
DISPLAY INVISIBLE (-2075 525);
FORCEPROP 0 LAST CDS_SEC 1
J 0
(-2075 525);
DISPLAY 1.021277 (-2075 525);
DISPLAY INVISIBLE (-2075 525);
FORCEPROP 1 LASTPIN (-2125 450) $PN 1
J 0
(-2120 412);
DISPLAY 0.787234 (-2120 412);
PAINT MONO (-2120 412);
FORCEPROP 1 LASTPIN (-2125 250) $PN 2
J 0
(-2120 260);
DISPLAY 0.787234 (-2120 260);
PAINT MONO (-2120 260);
FORCEPROP 1 LAST PACK_TYPE 0402LF
J 0
(-2085 175);
DISPLAY 0.510638 (-2085 175);
FORCEPROP 1 LAST WATTAGE 1/16W
J 0
(-2085 325);
DISPLAY 0.510638 (-2085 325);
FORCEPROP 1 LAST TOLERANCE 1%
J 0
(-2080 375);
DISPLAY 0.510638 (-2080 375);
FORCEPROP 1 LAST VALUE 100K
J 0
(-2080 425);
DISPLAY 0.510638 (-2080 425);
FORCEPROP 1 LAST MATERIAL EMPTY
J 0
(-2085 275);
DISPLAY 0.510638 (-2085 275);
PAINT RED (-2085 275);
FORCEPROP 2 LAST CDS_LIB pure_quanta
J 0
(-2125 350);
DISPLAY INVISIBLE (-2125 350);
FORCEPROP 1 LAST PATH I13
J 0
(-2075 525);
DISPLAY 0.978723 (-2075 525);
PAINT WHITE (-2075 525);
DISPLAY INVISIBLE (-2075 525);
FORCEPROP 1 LAST PART_NUMBER CS41002FB09
J 0
(-2085 225);
DISPLAY 0.510638 (-2085 225);
DISPLAY INVISIBLE (-2085 225);
FORCEADD Q_CAP..1
(5575 3975);
FORCEPROP 1 LAST LOCATION C16
J 0
(5625 4075);
DISPLAY 0.978723 (5625 4075);
FORCEPROP 0 LAST $SEC 1
J 0
(5625 4125);
DISPLAY 0.680851 (5625 4125);
PAINT MONO (5625 4125);
DISPLAY INVISIBLE (5625 4125);
FORCEPROP 0 LAST CDS_SEC 1
J 0
(5625 4125);
DISPLAY 1.021277 (5625 4125);
DISPLAY INVISIBLE (5625 4125);
FORCEPROP 1 LASTPIN (5575 4075) $PN 1
J 0
(5585 4055);
DISPLAY 0.787234 (5585 4055);
PAINT MONO (5585 4055);
FORCEPROP 1 LASTPIN (5575 3875) $PN 2
J 0
(5585 3855);
DISPLAY 0.787234 (5585 3855);
PAINT MONO (5585 3855);
FORCEPROP 1 LAST VOLTAGE 25V
J 0
(5625 3975);
DISPLAY 0.638298 (5625 3975);
FORCEPROP 1 LAST VALUE 0.1UF
J 0
(5625 4025);
DISPLAY 0.638298 (5625 4025);
FORCEPROP 1 LAST TOLERANCE 10%
J 0
(5625 3925);
DISPLAY 0.638298 (5625 3925);
FORCEPROP 1 LAST PACK_TYPE 0402
J 0
(5625 3775);
DISPLAY 0.638298 (5625 3775);
FORCEPROP 1 LAST MATERIAL X7R
J 0
(5625 3875);
DISPLAY 0.638298 (5625 3875);
PAINT RED (5625 3875);
FORCEPROP 2 LAST CDS_LIB pure_quanta
J 0
(5575 3975);
DISPLAY INVISIBLE (5575 3975);
FORCEPROP 1 LAST PATH I130
J 0
(5625 4125);
DISPLAY 0.978723 (5625 4125);
PAINT WHITE (5625 4125);
DISPLAY INVISIBLE (5625 4125);
FORCEPROP 1 LAST PART_NUMBER CH4104K1B00
J 0
(5625 3825);
DISPLAY 0.638298 (5625 3825);
DISPLAY INVISIBLE (5625 3825);
FORCEADD Q_RES..2
(4800 4450);
FORCEPROP 1 LAST LOCATION R4140
J 0
(4845 4575);
DISPLAY 0.638298 (4845 4575);
FORCEPROP 2 LAST $SEC 1
J 0
(4850 4675);
DISPLAY 0.680851 (4850 4675);
PAINT MONO (4850 4675);
DISPLAY INVISIBLE (4850 4675);
FORCEPROP 2 LAST CDS_SEC 1
J 0
(4850 4675);
DISPLAY 1.021277 (4850 4675);
DISPLAY INVISIBLE (4850 4675);
FORCEPROP 1 LASTPIN (4800 4550) $PN 1
J 0
(4805 4512);
DISPLAY 0.787234 (4805 4512);
FORCEPROP 1 LASTPIN (4800 4350) $PN 2
J 0
(4805 4360);
DISPLAY 0.787234 (4805 4360);
FORCEPROP 1 LAST VALUE 100K
J 0
(4845 4525);
DISPLAY 0.638298 (4845 4525);
FORCEPROP 1 LAST TOLERANCE 1%
J 0
(4845 4475);
DISPLAY 0.638298 (4845 4475);
FORCEPROP 1 LAST WATTAGE 1/16W
J 0
(4840 4425);
DISPLAY 0.638298 (4840 4425);
FORCEPROP 1 LAST PACK_TYPE 0402LF
J 0
(4840 4325);
DISPLAY 0.638298 (4840 4325);
FORCEPROP 1 LAST MATERIAL CHIP
J 0
(4840 4375);
DISPLAY 0.638298 (4840 4375);
FORCEPROP 2 LAST CDS_LIB pure_quanta
J 0
(4800 4450);
PAINT MONO (4800 4450);
DISPLAY INVISIBLE (4800 4450);
FORCEPROP 1 LAST PATH I131
J 0
(4850 4625);
DISPLAY 0.978723 (4850 4625);
PAINT WHITE (4850 4625);
DISPLAY INVISIBLE (4850 4625);
FORCEPROP 1 LAST PART_NUMBER CS41002FB09
J 0
(4840 4275);
DISPLAY 0.638298 (4840 4275);
DISPLAY INVISIBLE (4840 4275);
FORCEADD UNIVERSAL_POWER..1
(4800 4675);
FORCEPROP 3 LASTPIN (4800 4625) SIG_NAME P3V3_AUX\g
J 0
(4810 4635);
DISPLAY 0.659574 (4810 4635);
PAINT MONO (4810 4635);
DISPLAY INVISIBLE (4810 4635);
FORCEPROP 1 LAST HDL_POWER P3V3_AUX
J 1
(4800 4725);
DISPLAY 0.872340 (4800 4725);
PAINT GREEN (4800 4725);
FORCEPROP 2 LAST CDS_LIB pure_quanta_power
J 0
(4800 4675);
PAINT MONO (4800 4675);
DISPLAY INVISIBLE (4800 4675);
FORCEPROP 1 LAST PATH I132
J 0
(4850 4700);
DISPLAY 0.872340 (4850 4700);
PAINT AQUA (4850 4700);
DISPLAY INVISIBLE (4850 4700);
FORCEADD OFFPAGE..2
(5925 4275);
FORCEPROP 2 LAST $XR0 80 
J 0
(6114 4275);
DISPLAY 0.638298 (6114 4275);
PAINT MONO (6114 4275);
FORCEPROP 2 LAST CDS_LIB standard
J 0
(5925 4275);
DISPLAY INVISIBLE (5925 4275);
FORCEPROP 1 LAST OFFPAGE TRUE
J 0
(6250 4150);
DISPLAY 0.872340 (6250 4150);
PAINT AQUA (6250 4150);
DISPLAY INVISIBLE (6250 4150);
FORCEPROP 1 LAST COMMENT_BODY TRUE
J 0
(5880 4180);
DISPLAY 0.872340 (5880 4180);
PAINT GREEN (5880 4180);
DISPLAY INVISIBLE (5880 4180);
FORCEPROP 2 LAST PATH I133
J 0
(6125 4325);
DISPLAY 0.680851 (6125 4325);
DISPLAY INVISIBLE (6125 4325);
FORCEADD MOSFET_NCH_DUAL..2
(4750 -275);
FORCEPROP 1 LAST LOCATION Q146
J 0
(4901 -299);
DISPLAY 0.723404 (4901 -299);
PAINT GREEN (4901 -299);
FORCEPROP 0 LAST $SEC 2
J 0
(4925 -150);
DISPLAY 0.680851 (4925 -150);
PAINT MONO (4925 -150);
DISPLAY INVISIBLE (4925 -150);
FORCEPROP 0 LAST CDS_SEC 2
J 0
(4925 -150);
DISPLAY 1.021277 (4925 -150);
DISPLAY INVISIBLE (4925 -150);
FORCEPROP 0 LASTPIN (4800 -75) $PN 3
R 1
J 0
(4790 -65);
DISPLAY 0.680851 (4790 -65);
PAINT MONO (4790 -65);
FORCEPROP 0 LASTPIN (4550 -325) $PN 5
J 2
(4540 -315);
DISPLAY 0.680851 (4540 -315);
PAINT MONO (4540 -315);
FORCEPROP 0 LASTPIN (4800 -475) $PN 4
R 1
J 2
(4790 -485);
DISPLAY 0.680851 (4790 -485);
PAINT MONO (4790 -485);
FORCEPROP 2 LAST PART_TYPE SMLF
J 0
(4925 -200);
DISPLAY 1.021277 (4925 -200);
FORCEPROP 1 LAST MATERIAL IC
J 0
(4901 -424);
DISPLAY 0.723404 (4901 -424);
PAINT GREEN (4901 -424);
FORCEPROP 2 LAST VALUE PJT138K
J 0
(4925 -250);
DISPLAY 1.021277 (4925 -250);
FORCEPROP 1 LAST CDS_LMAN_SYM_OUTLINE -150,150,150,-150
J 0
(4750 -275);
DISPLAY 0.468085 (4750 -275);
PAINT GREEN (4750 -275);
DISPLAY INVISIBLE (4750 -275);
FORCEPROP 1 LAST NEEDS_NO_SIZE TRUE
J 0
(4900 -384);
DISPLAY 0.468085 (4900 -384);
PAINT GREEN (4900 -384);
DISPLAY INVISIBLE (4900 -384);
FORCEPROP 2 LAST CDS_LIB pure_quanta
J 0
(4750 -275);
DISPLAY INVISIBLE (4750 -275);
FORCEPROP 1 LAST PATH I134
J 0
(4900 -425);
DISPLAY 0.723404 (4900 -425);
PAINT GREEN (4900 -425);
DISPLAY INVISIBLE (4900 -425);
FORCEPROP 1 LAST PART_NUMBER BAM138K0003
J 0
(4901 -369);
DISPLAY 0.723404 (4901 -369);
PAINT GREEN (4901 -369);
DISPLAY INVISIBLE (4901 -369);
FORCEADD Q_RES..2
(-2100 1800);
FORCEPROP 1 LAST LOCATION R4124
J 0
(-2055 1925);
DISPLAY 0.978723 (-2055 1925);
FORCEPROP 0 LAST $SEC 1
J 0
(-2050 1975);
DISPLAY 0.680851 (-2050 1975);
PAINT MONO (-2050 1975);
DISPLAY INVISIBLE (-2050 1975);
FORCEPROP 0 LAST CDS_SEC 1
J 0
(-2050 1975);
DISPLAY 1.021277 (-2050 1975);
DISPLAY INVISIBLE (-2050 1975);
FORCEPROP 1 LASTPIN (-2100 1900) $PN 1
J 0
(-2095 1862);
DISPLAY 0.787234 (-2095 1862);
PAINT MONO (-2095 1862);
FORCEPROP 1 LASTPIN (-2100 1700) $PN 2
J 0
(-2095 1710);
DISPLAY 0.787234 (-2095 1710);
PAINT MONO (-2095 1710);
FORCEPROP 1 LAST MATERIAL EMPTY
J 0
(-2060 1725);
DISPLAY 0.510638 (-2060 1725);
PAINT RED (-2060 1725);
FORCEPROP 1 LAST TOLERANCE 1%
J 0
(-2055 1825);
DISPLAY 0.510638 (-2055 1825);
FORCEPROP 1 LAST VALUE 100K
J 0
(-2055 1875);
DISPLAY 0.510638 (-2055 1875);
FORCEPROP 1 LAST PACK_TYPE 0402LF
J 0
(-2060 1625);
DISPLAY 0.510638 (-2060 1625);
FORCEPROP 1 LAST WATTAGE 1/16W
J 0
(-2060 1775);
DISPLAY 0.510638 (-2060 1775);
FORCEPROP 2 LAST CDS_LIB pure_quanta
J 0
(-2100 1800);
DISPLAY INVISIBLE (-2100 1800);
FORCEPROP 1 LAST PATH I135
J 0
(-2050 1975);
DISPLAY 0.978723 (-2050 1975);
PAINT WHITE (-2050 1975);
DISPLAY INVISIBLE (-2050 1975);
FORCEPROP 1 LAST PART_NUMBER CS41002FB09
J 0
(-2060 1675);
DISPLAY 0.510638 (-2060 1675);
DISPLAY INVISIBLE (-2060 1675);
FORCEADD Q_RES..2
(-2150 825);
FORCEPROP 1 LAST LOCATION R4121
J 0
(-2105 950);
DISPLAY 0.978723 (-2105 950);
FORCEPROP 0 LAST $SEC 1
J 0
(-2100 1000);
DISPLAY 0.680851 (-2100 1000);
PAINT MONO (-2100 1000);
DISPLAY INVISIBLE (-2100 1000);
FORCEPROP 0 LAST CDS_SEC 1
J 0
(-2100 1000);
DISPLAY 1.021277 (-2100 1000);
DISPLAY INVISIBLE (-2100 1000);
FORCEPROP 1 LASTPIN (-2150 925) $PN 1
J 0
(-2145 887);
DISPLAY 0.787234 (-2145 887);
PAINT MONO (-2145 887);
FORCEPROP 1 LASTPIN (-2150 725) $PN 2
J 0
(-2145 735);
DISPLAY 0.787234 (-2145 735);
PAINT MONO (-2145 735);
FORCEPROP 1 LAST TOLERANCE 1%
J 0
(-2105 850);
DISPLAY 0.978723 (-2105 850);
FORCEPROP 1 LAST PACK_TYPE 0402LF
J 0
(-2110 650);
DISPLAY 0.978723 (-2110 650);
FORCEPROP 1 LAST VALUE 10K
J 0
(-2105 900);
DISPLAY 0.978723 (-2105 900);
FORCEPROP 1 LAST MATERIAL CHIP
J 0
(-2110 750);
DISPLAY 0.978723 (-2110 750);
FORCEPROP 1 LAST WATTAGE 1/16W
J 0
(-2110 800);
DISPLAY 0.978723 (-2110 800);
FORCEPROP 2 LAST CDS_LIB pure_quanta
J 0
(-2150 825);
DISPLAY INVISIBLE (-2150 825);
FORCEPROP 1 LAST PATH I14
J 0
(-2100 1000);
DISPLAY 0.978723 (-2100 1000);
PAINT WHITE (-2100 1000);
DISPLAY INVISIBLE (-2100 1000);
FORCEPROP 1 LAST PART_NUMBER CS31002FB08
J 0
(-2110 700);
DISPLAY 0.978723 (-2110 700);
DISPLAY INVISIBLE (-2110 700);
FORCEADD OFFPAGE..4
R 2
(-2375 2000);
FORCEPROP 2 LAST $XR0 119 
J 0
(-2627 2000);
DISPLAY 0.638298 (-2627 2000);
PAINT MONO (-2627 2000);
FORCEPROP 2 LAST CDS_LIB standard
J 0
(-2375 2000);
DISPLAY INVISIBLE (-2375 2000);
FORCEPROP 1 LAST OFFPAGE TRUE
J 2
(-2700 1875);
DISPLAY 0.872340 (-2700 1875);
PAINT GREEN (-2700 1875);
DISPLAY INVISIBLE (-2700 1875);
FORCEPROP 1 LAST COMMENT_BODY TRUE
J 2
(-2350 1900);
DISPLAY 0.872340 (-2350 1900);
PAINT GREEN (-2350 1900);
DISPLAY INVISIBLE (-2350 1900);
FORCEPROP 2 LAST PATH I15
J 0
(-2625 2050);
DISPLAY 0.680851 (-2625 2050);
DISPLAY INVISIBLE (-2625 2050);
FORCEADD UNIVERSAL_POWER..1
(-2150 1075);
FORCEPROP 3 LASTPIN (-2150 1025) SIG_NAME P3V3_AUX\g
J 0
(-2140 1035);
DISPLAY 0.659574 (-2140 1035);
PAINT MONO (-2140 1035);
DISPLAY INVISIBLE (-2140 1035);
FORCEPROP 1 LAST HDL_POWER P3V3_AUX
J 1
(-2150 1125);
DISPLAY 0.872340 (-2150 1125);
PAINT GREEN (-2150 1125);
FORCEPROP 2 LAST CDS_LIB pure_quanta_power
J 0
(-2150 1075);
PAINT MONO (-2150 1075);
DISPLAY INVISIBLE (-2150 1075);
FORCEPROP 1 LAST PATH I16
J 0
(-2100 1100);
DISPLAY 0.872340 (-2100 1100);
PAINT AQUA (-2100 1100);
DISPLAY INVISIBLE (-2100 1100);
FORCEADD UNIVERSAL_GND..1
(-2100 1525);
FORCEPROP 3 LASTPIN (-2100 1575) SIG_NAME GND\g
J 0
(-2090 1585);
DISPLAY 0.659574 (-2090 1585);
PAINT MONO (-2090 1585);
DISPLAY INVISIBLE (-2090 1585);
FORCEPROP 2 LAST CDS_LIB pure_quanta_power
J 0
(-2100 1525);
DISPLAY INVISIBLE (-2100 1525);
FORCEPROP 1 LAST HDL_POWER GND
J 1
(-2075 1450);
DISPLAY 0.872340 (-2075 1450);
PAINT GREEN (-2075 1450);
DISPLAY INVISIBLE (-2075 1450);
FORCEPROP 1 LAST PATH I17
J 0
(-2025 1525);
DISPLAY 0.872340 (-2025 1525);
PAINT AQUA (-2025 1525);
DISPLAY INVISIBLE (-2025 1525);
FORCEADD Q_RES..2
(-2125 2275);
FORCEPROP 1 LAST LOCATION R4123
J 0
(-2080 2400);
DISPLAY 0.978723 (-2080 2400);
FORCEPROP 0 LAST $SEC 1
J 0
(-2075 2450);
DISPLAY 0.680851 (-2075 2450);
PAINT MONO (-2075 2450);
DISPLAY INVISIBLE (-2075 2450);
FORCEPROP 0 LAST CDS_SEC 1
J 0
(-2075 2450);
DISPLAY 1.021277 (-2075 2450);
DISPLAY INVISIBLE (-2075 2450);
FORCEPROP 1 LASTPIN (-2125 2375) $PN 1
J 0
(-2120 2337);
DISPLAY 0.787234 (-2120 2337);
PAINT MONO (-2120 2337);
FORCEPROP 1 LASTPIN (-2125 2175) $PN 2
J 0
(-2120 2185);
DISPLAY 0.787234 (-2120 2185);
PAINT MONO (-2120 2185);
FORCEPROP 1 LAST MATERIAL EMPTY
J 0
(-2085 2200);
DISPLAY 0.787234 (-2085 2200);
PAINT RED (-2085 2200);
FORCEPROP 1 LAST PACK_TYPE 0402LF
J 0
(-2085 2100);
DISPLAY 0.787234 (-2085 2100);
FORCEPROP 1 LAST WATTAGE 1/16W
J 0
(-2085 2250);
DISPLAY 0.787234 (-2085 2250);
FORCEPROP 1 LAST TOLERANCE 1%
J 0
(-2080 2300);
DISPLAY 0.787234 (-2080 2300);
FORCEPROP 1 LAST VALUE 54.9K
J 0
(-2080 2350);
DISPLAY 0.787234 (-2080 2350);
FORCEPROP 2 LAST CDS_LIB pure_quanta
J 0
(-2125 2275);
DISPLAY INVISIBLE (-2125 2275);
FORCEPROP 1 LAST PATH I18
J 0
(-2075 2450);
DISPLAY 0.978723 (-2075 2450);
PAINT WHITE (-2075 2450);
DISPLAY INVISIBLE (-2075 2450);
FORCEPROP 1 LAST PART_NUMBER CS35492FB03
J 0
(-2085 2150);
DISPLAY 0.787234 (-2085 2150);
DISPLAY INVISIBLE (-2085 2150);
FORCEADD UNIVERSAL_POWER..1
(-2125 2525);
FORCEPROP 3 LASTPIN (-2125 2475) SIG_NAME P3V3_AUX\g
J 0
(-2115 2485);
DISPLAY 0.659574 (-2115 2485);
PAINT MONO (-2115 2485);
DISPLAY INVISIBLE (-2115 2485);
FORCEPROP 1 LAST HDL_POWER P3V3_AUX
J 1
(-2125 2575);
DISPLAY 0.872340 (-2125 2575);
PAINT GREEN (-2125 2575);
FORCEPROP 2 LAST CDS_LIB pure_quanta_power
J 0
(-2125 2525);
PAINT MONO (-2125 2525);
DISPLAY INVISIBLE (-2125 2525);
FORCEPROP 1 LAST PATH I19
J 0
(-2075 2550);
DISPLAY 0.872340 (-2075 2550);
PAINT AQUA (-2075 2550);
DISPLAY INVISIBLE (-2075 2550);
FORCEADD Q_RES..2
(-2050 -1200);
FORCEPROP 1 LAST LOCATION R4154
J 0
(-2005 -1075);
DISPLAY 0.978723 (-2005 -1075);
FORCEPROP 0 LAST $SEC 1
J 0
(-2000 -1025);
DISPLAY 0.680851 (-2000 -1025);
PAINT MONO (-2000 -1025);
DISPLAY INVISIBLE (-2000 -1025);
FORCEPROP 0 LAST CDS_SEC 1
J 0
(-2000 -1025);
DISPLAY 1.021277 (-2000 -1025);
DISPLAY INVISIBLE (-2000 -1025);
FORCEPROP 1 LASTPIN (-2050 -1100) $PN 1
J 0
(-2045 -1138);
DISPLAY 0.787234 (-2045 -1138);
PAINT MONO (-2045 -1138);
FORCEPROP 1 LASTPIN (-2050 -1300) $PN 2
J 0
(-2045 -1290);
DISPLAY 0.787234 (-2045 -1290);
PAINT MONO (-2045 -1290);
FORCEPROP 1 LAST PACK_TYPE 0402LF
J 0
(-2010 -1375);
DISPLAY 0.510638 (-2010 -1375);
FORCEPROP 1 LAST TOLERANCE 1%
J 0
(-2005 -1175);
DISPLAY 0.510638 (-2005 -1175);
FORCEPROP 1 LAST VALUE 100K
J 0
(-2005 -1125);
DISPLAY 0.510638 (-2005 -1125);
FORCEPROP 1 LAST MATERIAL EMPTY
J 0
(-2010 -1275);
DISPLAY 0.510638 (-2010 -1275);
PAINT RED (-2010 -1275);
FORCEPROP 1 LAST WATTAGE 1/16W
J 0
(-2010 -1225);
DISPLAY 0.510638 (-2010 -1225);
FORCEPROP 2 LAST CDS_LIB pure_quanta
J 0
(-2050 -1200);
DISPLAY INVISIBLE (-2050 -1200);
FORCEPROP 1 LAST PATH I2
J 0
(-2000 -1025);
DISPLAY 0.978723 (-2000 -1025);
PAINT WHITE (-2000 -1025);
DISPLAY INVISIBLE (-2000 -1025);
FORCEPROP 1 LAST PART_NUMBER CS41002FB09
J 0
(-2010 -1325);
DISPLAY 0.510638 (-2010 -1325);
DISPLAY INVISIBLE (-2010 -1325);
FORCEADD UNIVERSAL_GND..1
(-2125 2900);
FORCEPROP 3 LASTPIN (-2125 2950) SIG_NAME GND\g
J 0
(-2115 2960);
DISPLAY 0.659574 (-2115 2960);
PAINT MONO (-2115 2960);
DISPLAY INVISIBLE (-2115 2960);
FORCEPROP 2 LAST CDS_LIB pure_quanta_power
J 0
(-2125 2900);
DISPLAY INVISIBLE (-2125 2900);
FORCEPROP 1 LAST HDL_POWER GND
J 1
(-2100 2825);
DISPLAY 0.872340 (-2100 2825);
PAINT GREEN (-2100 2825);
DISPLAY INVISIBLE (-2100 2825);
FORCEPROP 1 LAST PATH I20
J 0
(-2050 2900);
DISPLAY 0.872340 (-2050 2900);
PAINT AQUA (-2050 2900);
DISPLAY INVISIBLE (-2050 2900);
FORCEADD OFFPAGE..4
R 2
(-2400 3375);
FORCEPROP 2 LAST $XR0 119 
J 0
(-2652 3375);
DISPLAY 0.638298 (-2652 3375);
PAINT MONO (-2652 3375);
FORCEPROP 2 LAST CDS_LIB standard
J 0
(-2400 3375);
DISPLAY INVISIBLE (-2400 3375);
FORCEPROP 1 LAST OFFPAGE TRUE
J 2
(-2725 3250);
DISPLAY 0.872340 (-2725 3250);
PAINT GREEN (-2725 3250);
DISPLAY INVISIBLE (-2725 3250);
FORCEPROP 1 LAST COMMENT_BODY TRUE
J 2
(-2375 3275);
DISPLAY 0.872340 (-2375 3275);
PAINT GREEN (-2375 3275);
DISPLAY INVISIBLE (-2375 3275);
FORCEPROP 2 LAST PATH I21
J 0
(-2675 3425);
DISPLAY 0.680851 (-2675 3425);
DISPLAY INVISIBLE (-2675 3425);
FORCEADD Q_RES..2
(-2125 3175);
FORCEPROP 1 LAST LOCATION R4120
J 0
(-2080 3300);
DISPLAY 0.978723 (-2080 3300);
FORCEPROP 0 LAST $SEC 1
J 0
(-2075 3350);
DISPLAY 0.680851 (-2075 3350);
PAINT MONO (-2075 3350);
DISPLAY INVISIBLE (-2075 3350);
FORCEPROP 0 LAST CDS_SEC 1
J 0
(-2075 3350);
DISPLAY 1.021277 (-2075 3350);
DISPLAY INVISIBLE (-2075 3350);
FORCEPROP 1 LASTPIN (-2125 3275) $PN 1
J 0
(-2120 3237);
DISPLAY 0.787234 (-2120 3237);
PAINT MONO (-2120 3237);
FORCEPROP 1 LASTPIN (-2125 3075) $PN 2
J 0
(-2120 3085);
DISPLAY 0.787234 (-2120 3085);
PAINT MONO (-2120 3085);
FORCEPROP 1 LAST MATERIAL EMPTY
J 0
(-2085 3100);
DISPLAY 0.510638 (-2085 3100);
PAINT RED (-2085 3100);
FORCEPROP 1 LAST WATTAGE 1/16W
J 0
(-2085 3150);
DISPLAY 0.510638 (-2085 3150);
FORCEPROP 1 LAST TOLERANCE 1%
J 0
(-2080 3200);
DISPLAY 0.510638 (-2080 3200);
FORCEPROP 1 LAST VALUE 100K
J 0
(-2080 3250);
DISPLAY 0.510638 (-2080 3250);
FORCEPROP 1 LAST PACK_TYPE 0402LF
J 0
(-2085 3000);
DISPLAY 0.510638 (-2085 3000);
FORCEPROP 2 LAST CDS_LIB pure_quanta
J 0
(-2125 3175);
DISPLAY INVISIBLE (-2125 3175);
FORCEPROP 1 LAST PATH I22
J 0
(-2075 3350);
DISPLAY 0.978723 (-2075 3350);
PAINT WHITE (-2075 3350);
DISPLAY INVISIBLE (-2075 3350);
FORCEPROP 1 LAST PART_NUMBER CS41002FB09
J 0
(-2085 3050);
DISPLAY 0.510638 (-2085 3050);
DISPLAY INVISIBLE (-2085 3050);
FORCEADD Q_RES..2
(-2150 3650);
FORCEPROP 1 LAST LOCATION R4119
J 0
(-2105 3775);
DISPLAY 0.978723 (-2105 3775);
FORCEPROP 0 LAST $SEC 1
J 0
(-2100 3825);
DISPLAY 0.680851 (-2100 3825);
PAINT MONO (-2100 3825);
DISPLAY INVISIBLE (-2100 3825);
FORCEPROP 0 LAST CDS_SEC 1
J 0
(-2100 3825);
DISPLAY 1.021277 (-2100 3825);
DISPLAY INVISIBLE (-2100 3825);
FORCEPROP 1 LASTPIN (-2150 3750) $PN 1
J 0
(-2145 3712);
DISPLAY 0.787234 (-2145 3712);
PAINT MONO (-2145 3712);
FORCEPROP 1 LASTPIN (-2150 3550) $PN 2
J 0
(-2145 3560);
DISPLAY 0.787234 (-2145 3560);
PAINT MONO (-2145 3560);
FORCEPROP 1 LAST MATERIAL EMPTY
J 0
(-2110 3575);
DISPLAY 0.787234 (-2110 3575);
PAINT RED (-2110 3575);
FORCEPROP 1 LAST WATTAGE 1/16W
J 0
(-2110 3625);
DISPLAY 0.787234 (-2110 3625);
FORCEPROP 1 LAST VALUE 54.9K
J 0
(-2105 3725);
DISPLAY 0.787234 (-2105 3725);
FORCEPROP 1 LAST TOLERANCE 1%
J 0
(-2105 3675);
DISPLAY 0.787234 (-2105 3675);
FORCEPROP 1 LAST PACK_TYPE 0402LF
J 0
(-2110 3475);
DISPLAY 0.787234 (-2110 3475);
FORCEPROP 2 LAST CDS_LIB pure_quanta
J 0
(-2150 3650);
DISPLAY INVISIBLE (-2150 3650);
FORCEPROP 1 LAST PATH I23
J 0
(-2100 3825);
DISPLAY 0.978723 (-2100 3825);
PAINT WHITE (-2100 3825);
DISPLAY INVISIBLE (-2100 3825);
FORCEPROP 1 LAST PART_NUMBER CS35492FB03
J 0
(-2110 3525);
DISPLAY 0.787234 (-2110 3525);
DISPLAY INVISIBLE (-2110 3525);
FORCEADD UNIVERSAL_POWER..1
(-2150 3900);
FORCEPROP 3 LASTPIN (-2150 3850) SIG_NAME P3V3_AUX\g
J 0
(-2140 3860);
DISPLAY 0.659574 (-2140 3860);
PAINT MONO (-2140 3860);
DISPLAY INVISIBLE (-2140 3860);
FORCEPROP 1 LAST HDL_POWER P3V3_AUX
J 1
(-2150 3950);
DISPLAY 0.872340 (-2150 3950);
PAINT GREEN (-2150 3950);
FORCEPROP 2 LAST CDS_LIB pure_quanta_power
J 0
(-2150 3900);
PAINT MONO (-2150 3900);
DISPLAY INVISIBLE (-2150 3900);
FORCEPROP 1 LAST PATH I24
J 0
(-2100 3925);
DISPLAY 0.872340 (-2100 3925);
PAINT AQUA (-2100 3925);
DISPLAY INVISIBLE (-2100 3925);
FORCEADD MOSFET_NCH_DUAL..1
(-1025 600);
FORCEPROP 1 LAST LOCATION Q132
J 0
(-874 574);
DISPLAY 0.723404 (-874 574);
PAINT GREEN (-874 574);
FORCEPROP 0 LAST $SEC 1
J 0
(-850 725);
DISPLAY 0.680851 (-850 725);
PAINT MONO (-850 725);
DISPLAY INVISIBLE (-850 725);
FORCEPROP 2 LAST CDS_SEC 1
J 0
(-850 725);
DISPLAY 1.021277 (-850 725);
DISPLAY INVISIBLE (-850 725);
FORCEPROP 0 LASTPIN (-975 800) $PN 6
R 1
J 0
(-985 810);
DISPLAY 0.680851 (-985 810);
PAINT MONO (-985 810);
FORCEPROP 0 LASTPIN (-1225 550) $PN 2
J 2
(-1235 560);
DISPLAY 0.680851 (-1235 560);
PAINT MONO (-1235 560);
FORCEPROP 0 LASTPIN (-975 400) $PN 1
R 1
J 2
(-985 390);
DISPLAY 0.680851 (-985 390);
PAINT MONO (-985 390);
FORCEPROP 1 LAST MATERIAL IC
J 0
(-874 449);
DISPLAY 0.723404 (-874 449);
PAINT GREEN (-874 449);
FORCEPROP 2 LAST PART_TYPE SMLF
J 0
(-850 675);
DISPLAY 1.021277 (-850 675);
FORCEPROP 2 LAST VALUE PJT138K
J 0
(-850 625);
DISPLAY 1.021277 (-850 625);
FORCEPROP 2 LAST CDS_LIB pure_quanta
J 0
(-1025 600);
DISPLAY INVISIBLE (-1025 600);
FORCEPROP 1 LAST NEEDS_NO_SIZE TRUE
J 0
(-1025 599);
DISPLAY 0.468085 (-1025 599);
PAINT GREEN (-1025 599);
DISPLAY INVISIBLE (-1025 599);
FORCEPROP 1 LAST CDS_LMAN_SYM_OUTLINE -150,150,150,-150
J 0
(-1025 600);
DISPLAY 0.468085 (-1025 600);
PAINT GREEN (-1025 600);
DISPLAY INVISIBLE (-1025 600);
FORCEPROP 1 LAST PATH I25
J 0
(-1025 600);
DISPLAY 0.723404 (-1025 600);
PAINT GREEN (-1025 600);
DISPLAY INVISIBLE (-1025 600);
FORCEPROP 1 LAST PART_NUMBER BAM138K0003
J 0
(-874 514);
DISPLAY 0.723404 (-874 514);
PAINT GREEN (-874 514);
DISPLAY INVISIBLE (-874 514);
FORCEADD UNIVERSAL_GND..1
(-975 225);
FORCEPROP 3 LASTPIN (-975 275) SIG_NAME GND\g
J 0
(-965 285);
DISPLAY 0.659574 (-965 285);
PAINT MONO (-965 285);
DISPLAY INVISIBLE (-965 285);
FORCEPROP 2 LAST CDS_LIB pure_quanta_power
J 0
(-975 225);
DISPLAY INVISIBLE (-975 225);
FORCEPROP 1 LAST HDL_POWER GND
J 1
(-950 150);
DISPLAY 0.872340 (-950 150);
PAINT GREEN (-950 150);
DISPLAY INVISIBLE (-950 150);
FORCEPROP 1 LAST PATH I26
J 0
(-900 225);
DISPLAY 0.872340 (-900 225);
PAINT AQUA (-900 225);
DISPLAY INVISIBLE (-900 225);
FORCEADD Q_RES..2
(-975 1200);
FORCEPROP 1 LAST LOCATION R4126
J 0
(-930 1325);
DISPLAY 0.638298 (-930 1325);
FORCEPROP 2 LAST $SEC 1
J 0
(-925 1425);
DISPLAY 0.680851 (-925 1425);
PAINT MONO (-925 1425);
DISPLAY INVISIBLE (-925 1425);
FORCEPROP 2 LAST CDS_SEC 1
J 0
(-925 1425);
DISPLAY 1.021277 (-925 1425);
DISPLAY INVISIBLE (-925 1425);
FORCEPROP 1 LASTPIN (-975 1300) $PN 1
J 0
(-970 1262);
DISPLAY 0.787234 (-970 1262);
FORCEPROP 1 LASTPIN (-975 1100) $PN 2
J 0
(-970 1110);
DISPLAY 0.787234 (-970 1110);
FORCEPROP 1 LAST WATTAGE 1/16W
J 0
(-935 1175);
DISPLAY 0.638298 (-935 1175);
FORCEPROP 1 LAST TOLERANCE 5%
J 0
(-930 1225);
DISPLAY 0.638298 (-930 1225);
FORCEPROP 1 LAST MATERIAL CHIP
J 0
(-935 1125);
DISPLAY 0.638298 (-935 1125);
FORCEPROP 1 LAST VALUE 4.7K
J 0
(-930 1275);
DISPLAY 0.638298 (-930 1275);
FORCEPROP 1 LAST PACK_TYPE 0402LF
J 0
(-935 1075);
DISPLAY 0.638298 (-935 1075);
FORCEPROP 2 LAST CDS_LIB pure_quanta
J 0
(-975 1200);
PAINT MONO (-975 1200);
DISPLAY INVISIBLE (-975 1200);
FORCEPROP 1 LAST PATH I27
J 0
(-925 1375);
DISPLAY 0.978723 (-925 1375);
PAINT WHITE (-925 1375);
DISPLAY INVISIBLE (-925 1375);
FORCEPROP 1 LAST PART_NUMBER CS24702JB10
J 0
(-935 1025);
DISPLAY 0.638298 (-935 1025);
DISPLAY INVISIBLE (-935 1025);
FORCEADD UNIVERSAL_POWER..1
(-975 1425);
FORCEPROP 3 LASTPIN (-975 1375) SIG_NAME P3V3_AUX\g
J 0
(-965 1385);
DISPLAY 0.659574 (-965 1385);
PAINT MONO (-965 1385);
DISPLAY INVISIBLE (-965 1385);
FORCEPROP 1 LAST HDL_POWER P3V3_AUX
J 1
(-975 1475);
DISPLAY 0.872340 (-975 1475);
PAINT GREEN (-975 1475);
FORCEPROP 2 LAST CDS_LIB pure_quanta_power
J 0
(-975 1425);
PAINT MONO (-975 1425);
DISPLAY INVISIBLE (-975 1425);
FORCEPROP 1 LAST PATH I28
J 0
(-925 1450);
DISPLAY 0.872340 (-925 1450);
PAINT AQUA (-925 1450);
DISPLAY INVISIBLE (-925 1450);
FORCEADD UNIVERSAL_GND..1
(-950 1675);
FORCEPROP 3 LASTPIN (-950 1725) SIG_NAME GND\g
J 0
(-940 1735);
DISPLAY 0.659574 (-940 1735);
PAINT MONO (-940 1735);
DISPLAY INVISIBLE (-940 1735);
FORCEPROP 2 LAST CDS_LIB pure_quanta_power
J 0
(-950 1675);
DISPLAY INVISIBLE (-950 1675);
FORCEPROP 1 LAST HDL_POWER GND
J 1
(-925 1600);
DISPLAY 0.872340 (-925 1600);
PAINT GREEN (-925 1600);
DISPLAY INVISIBLE (-925 1600);
FORCEPROP 1 LAST PATH I29
J 0
(-875 1675);
DISPLAY 0.872340 (-875 1675);
PAINT AQUA (-875 1675);
DISPLAY INVISIBLE (-875 1675);
FORCEADD OFFPAGE..4
R 2
(-2325 -1000);
FORCEPROP 2 LAST $XR0 116 
J 0
(-2607 -1000);
DISPLAY 0.638298 (-2607 -1000);
PAINT MONO (-2607 -1000);
FORCEPROP 2 LAST CDS_LIB standard
J 0
(-2325 -1000);
DISPLAY INVISIBLE (-2325 -1000);
FORCEPROP 1 LAST OFFPAGE TRUE
J 2
(-2650 -1125);
DISPLAY 0.872340 (-2650 -1125);
PAINT GREEN (-2650 -1125);
DISPLAY INVISIBLE (-2650 -1125);
FORCEPROP 1 LAST COMMENT_BODY TRUE
J 2
(-2300 -1100);
DISPLAY 0.872340 (-2300 -1100);
PAINT GREEN (-2300 -1100);
DISPLAY INVISIBLE (-2300 -1100);
FORCEPROP 2 LAST PATH I3
J 0
(-2575 -950);
DISPLAY 0.680851 (-2575 -950);
DISPLAY INVISIBLE (-2575 -950);
FORCEADD MOSFET_NCH_DUAL..1
(-1000 2050);
FORCEPROP 1 LAST LOCATION Q131
J 0
(-849 2024);
DISPLAY 0.723404 (-849 2024);
PAINT GREEN (-849 2024);
FORCEPROP 0 LAST $SEC 1
J 0
(-825 2175);
DISPLAY 0.680851 (-825 2175);
PAINT MONO (-825 2175);
DISPLAY INVISIBLE (-825 2175);
FORCEPROP 2 LAST CDS_SEC 1
J 0
(-825 2175);
DISPLAY 1.021277 (-825 2175);
DISPLAY INVISIBLE (-825 2175);
FORCEPROP 0 LASTPIN (-950 2250) $PN 6
R 1
J 0
(-960 2260);
DISPLAY 0.680851 (-960 2260);
PAINT MONO (-960 2260);
FORCEPROP 0 LASTPIN (-1200 2000) $PN 2
J 2
(-1210 2010);
DISPLAY 0.680851 (-1210 2010);
PAINT MONO (-1210 2010);
FORCEPROP 0 LASTPIN (-950 1850) $PN 1
R 1
J 2
(-960 1840);
DISPLAY 0.680851 (-960 1840);
PAINT MONO (-960 1840);
FORCEPROP 2 LAST VALUE PJT138K
J 0
(-825 2075);
DISPLAY 1.021277 (-825 2075);
FORCEPROP 2 LAST PART_TYPE SMLF
J 0
(-825 2125);
DISPLAY 1.021277 (-825 2125);
FORCEPROP 1 LAST MATERIAL IC
J 0
(-849 1899);
DISPLAY 0.723404 (-849 1899);
PAINT GREEN (-849 1899);
FORCEPROP 1 LAST CDS_LMAN_SYM_OUTLINE -150,150,150,-150
J 0
(-1000 2050);
DISPLAY 0.468085 (-1000 2050);
PAINT GREEN (-1000 2050);
DISPLAY INVISIBLE (-1000 2050);
FORCEPROP 1 LAST NEEDS_NO_SIZE TRUE
J 0
(-1000 2049);
DISPLAY 0.468085 (-1000 2049);
PAINT GREEN (-1000 2049);
DISPLAY INVISIBLE (-1000 2049);
FORCEPROP 2 LAST CDS_LIB pure_quanta
J 0
(-1000 2050);
DISPLAY INVISIBLE (-1000 2050);
FORCEPROP 1 LAST PATH I30
J 0
(-1000 2050);
DISPLAY 0.723404 (-1000 2050);
PAINT GREEN (-1000 2050);
DISPLAY INVISIBLE (-1000 2050);
FORCEPROP 1 LAST PART_NUMBER BAM138K0003
J 0
(-849 1964);
DISPLAY 0.723404 (-849 1964);
PAINT GREEN (-849 1964);
DISPLAY INVISIBLE (-849 1964);
FORCEADD Q_RES..1
(-625 25);
FORCEPROP 1 LAST LOCATION R4574
J 0
(-875 25);
DISPLAY 0.787234 (-875 25);
FORCEPROP 0 LAST $SEC 1
J 0
(-375 150);
DISPLAY 0.680851 (-375 150);
PAINT MONO (-375 150);
DISPLAY INVISIBLE (-375 150);
FORCEPROP 0 LAST CDS_SEC 1
J 0
(-375 150);
DISPLAY 1.021277 (-375 150);
DISPLAY INVISIBLE (-375 150);
FORCEPROP 1 LASTPIN (-725 25) $PN 1
J 0
(-713 37);
DISPLAY 0.787234 (-713 37);
PAINT MONO (-713 37);
FORCEPROP 1 LASTPIN (-525 25) $PN 2
J 0
(-563 37);
DISPLAY 0.787234 (-563 37);
PAINT MONO (-563 37);
FORCEPROP 1 LAST VALUE 0
J 2
(-500 25);
DISPLAY 0.510638 (-500 25);
FORCEPROP 1 LAST TOLERANCE 5%
J 0
(-475 25);
DISPLAY 0.510638 (-475 25);
FORCEPROP 1 LAST MATERIAL EMPTY
J 0
(-400 25);
DISPLAY 0.510638 (-400 25);
PAINT RED (-400 25);
FORCEPROP 1 LAST WATTAGE 1/16W
J 2
(-375 125);
DISPLAY 0.510638 (-375 125);
FORCEPROP 1 LAST PACK_TYPE 0402LF
J 0
(-725 125);
DISPLAY 0.510638 (-725 125);
FORCEPROP 2 LAST CDS_LIB pure_quanta
J 0
(-625 25);
DISPLAY INVISIBLE (-625 25);
FORCEPROP 1 LAST PATH I31
J 0
(-675 175);
DISPLAY 0.978723 (-675 175);
PAINT WHITE (-675 175);
DISPLAY INVISIBLE (-675 175);
FORCEPROP 1 LAST PART_NUMBER CS00002JB13
J 0
(-675 75);
DISPLAY 0.510638 (-675 75);
DISPLAY INVISIBLE (-675 75);
FORCEADD MOSFET_NCH_DUAL..2
(125 900);
FORCEPROP 1 LAST LOCATION Q132
J 0
(276 876);
DISPLAY 0.723404 (276 876);
PAINT GREEN (276 876);
FORCEPROP 0 LAST $SEC 2
J 0
(300 1025);
DISPLAY 0.680851 (300 1025);
PAINT MONO (300 1025);
DISPLAY INVISIBLE (300 1025);
FORCEPROP 0 LAST CDS_SEC 2
J 0
(300 1025);
DISPLAY 1.021277 (300 1025);
DISPLAY INVISIBLE (300 1025);
FORCEPROP 0 LASTPIN (175 1100) $PN 3
R 1
J 0
(165 1110);
DISPLAY 0.680851 (165 1110);
PAINT MONO (165 1110);
FORCEPROP 0 LASTPIN (-75 850) $PN 5
J 2
(-85 860);
DISPLAY 0.680851 (-85 860);
PAINT MONO (-85 860);
FORCEPROP 0 LASTPIN (175 700) $PN 4
R 1
J 2
(165 690);
DISPLAY 0.680851 (165 690);
PAINT MONO (165 690);
FORCEPROP 2 LAST PART_TYPE SMLF
J 0
(300 975);
DISPLAY 1.021277 (300 975);
FORCEPROP 1 LAST MATERIAL IC
J 0
(276 751);
DISPLAY 0.723404 (276 751);
PAINT GREEN (276 751);
FORCEPROP 2 LAST VALUE PJT138K
J 0
(300 925);
DISPLAY 1.021277 (300 925);
FORCEPROP 2 LAST CDS_LIB pure_quanta
J 0
(125 900);
DISPLAY INVISIBLE (125 900);
FORCEPROP 1 LAST NEEDS_NO_SIZE TRUE
J 0
(275 791);
DISPLAY 0.468085 (275 791);
PAINT GREEN (275 791);
DISPLAY INVISIBLE (275 791);
FORCEPROP 1 LAST CDS_LMAN_SYM_OUTLINE -150,150,150,-150
J 0
(125 900);
DISPLAY 0.468085 (125 900);
PAINT GREEN (125 900);
DISPLAY INVISIBLE (125 900);
FORCEPROP 1 LAST PATH I32
J 0
(275 750);
DISPLAY 0.723404 (275 750);
PAINT GREEN (275 750);
DISPLAY INVISIBLE (275 750);
FORCEPROP 1 LAST PART_NUMBER BAM138K0003
J 0
(276 806);
DISPLAY 0.723404 (276 806);
PAINT GREEN (276 806);
DISPLAY INVISIBLE (276 806);
FORCEADD Q_RES..1
(-700 1575);
FORCEPROP 1 LAST LOCATION R4573
J 0
(-950 1575);
DISPLAY 0.787234 (-950 1575);
FORCEPROP 0 LAST $SEC 1
J 0
(-450 1700);
DISPLAY 0.680851 (-450 1700);
PAINT MONO (-450 1700);
DISPLAY INVISIBLE (-450 1700);
FORCEPROP 0 LAST CDS_SEC 1
J 0
(-450 1700);
DISPLAY 1.021277 (-450 1700);
DISPLAY INVISIBLE (-450 1700);
FORCEPROP 1 LASTPIN (-800 1575) $PN 1
J 0
(-788 1587);
DISPLAY 0.787234 (-788 1587);
PAINT MONO (-788 1587);
FORCEPROP 1 LASTPIN (-600 1575) $PN 2
J 0
(-638 1587);
DISPLAY 0.787234 (-638 1587);
PAINT MONO (-638 1587);
FORCEPROP 1 LAST TOLERANCE 5%
J 0
(-550 1575);
DISPLAY 0.510638 (-550 1575);
FORCEPROP 1 LAST VALUE 0
J 2
(-575 1575);
DISPLAY 0.510638 (-575 1575);
FORCEPROP 1 LAST MATERIAL EMPTY
J 0
(-475 1575);
DISPLAY 0.510638 (-475 1575);
PAINT RED (-475 1575);
FORCEPROP 1 LAST WATTAGE 1/16W
J 2
(-450 1675);
DISPLAY 0.510638 (-450 1675);
FORCEPROP 1 LAST PACK_TYPE 0402LF
J 0
(-800 1675);
DISPLAY 0.510638 (-800 1675);
FORCEPROP 2 LAST CDS_LIB pure_quanta
J 0
(-700 1575);
DISPLAY INVISIBLE (-700 1575);
FORCEPROP 1 LAST PATH I33
J 0
(-750 1725);
DISPLAY 0.978723 (-750 1725);
PAINT WHITE (-750 1725);
DISPLAY INVISIBLE (-750 1725);
FORCEPROP 1 LAST PART_NUMBER CS00002JB13
J 0
(-750 1625);
DISPLAY 0.510638 (-750 1625);
DISPLAY INVISIBLE (-750 1625);
FORCEADD UNIVERSAL_POWER..1
(0 1475);
FORCEPROP 3 LASTPIN (0 1425) SIG_NAME P3V3_AUX\g
J 0
(10 1435);
DISPLAY 0.659574 (10 1435);
PAINT MONO (10 1435);
DISPLAY INVISIBLE (10 1435);
FORCEPROP 1 LAST HDL_POWER P3V3_AUX
J 1
(0 1525);
DISPLAY 0.872340 (0 1525);
PAINT GREEN (0 1525);
FORCEPROP 2 LAST CDS_LIB pure_quanta_power
J 0
(0 1475);
PAINT MONO (0 1475);
DISPLAY INVISIBLE (0 1475);
FORCEPROP 1 LAST PATH I34
J 0
(50 1500);
DISPLAY 0.872340 (50 1500);
PAINT AQUA (50 1500);
DISPLAY INVISIBLE (50 1500);
FORCEADD Q_RES..2
(-950 2650);
FORCEPROP 1 LAST LOCATION R4127
J 0
(-905 2775);
DISPLAY 0.638298 (-905 2775);
FORCEPROP 2 LAST $SEC 1
J 0
(-900 2875);
DISPLAY 0.680851 (-900 2875);
PAINT MONO (-900 2875);
DISPLAY INVISIBLE (-900 2875);
FORCEPROP 2 LAST CDS_SEC 1
J 0
(-900 2875);
DISPLAY 1.021277 (-900 2875);
DISPLAY INVISIBLE (-900 2875);
FORCEPROP 1 LASTPIN (-950 2750) $PN 1
J 0
(-945 2712);
DISPLAY 0.787234 (-945 2712);
FORCEPROP 1 LASTPIN (-950 2550) $PN 2
J 0
(-945 2560);
DISPLAY 0.787234 (-945 2560);
FORCEPROP 1 LAST TOLERANCE 5%
J 0
(-905 2675);
DISPLAY 0.638298 (-905 2675);
FORCEPROP 1 LAST PACK_TYPE 0402LF
J 0
(-910 2525);
DISPLAY 0.638298 (-910 2525);
FORCEPROP 1 LAST WATTAGE 1/16W
J 0
(-910 2625);
DISPLAY 0.638298 (-910 2625);
FORCEPROP 1 LAST MATERIAL CHIP
J 0
(-910 2575);
DISPLAY 0.638298 (-910 2575);
FORCEPROP 1 LAST VALUE 4.7K
J 0
(-905 2725);
DISPLAY 0.638298 (-905 2725);
FORCEPROP 2 LAST CDS_LIB pure_quanta
J 0
(-950 2650);
PAINT MONO (-950 2650);
DISPLAY INVISIBLE (-950 2650);
FORCEPROP 1 LAST PATH I35
J 0
(-900 2825);
DISPLAY 0.978723 (-900 2825);
PAINT WHITE (-900 2825);
DISPLAY INVISIBLE (-900 2825);
FORCEPROP 1 LAST PART_NUMBER CS24702JB10
J 0
(-910 2475);
DISPLAY 0.638298 (-910 2475);
DISPLAY INVISIBLE (-910 2475);
FORCEADD UNIVERSAL_POWER..1
(-950 2875);
FORCEPROP 3 LASTPIN (-950 2825) SIG_NAME P3V3_AUX\g
J 0
(-940 2835);
DISPLAY 0.659574 (-940 2835);
PAINT MONO (-940 2835);
DISPLAY INVISIBLE (-940 2835);
FORCEPROP 1 LAST HDL_POWER P3V3_AUX
J 1
(-950 2925);
DISPLAY 0.872340 (-950 2925);
PAINT GREEN (-950 2925);
FORCEPROP 2 LAST CDS_LIB pure_quanta_power
J 0
(-950 2875);
PAINT MONO (-950 2875);
DISPLAY INVISIBLE (-950 2875);
FORCEPROP 1 LAST PATH I36
J 0
(-900 2900);
DISPLAY 0.872340 (-900 2900);
PAINT AQUA (-900 2900);
DISPLAY INVISIBLE (-900 2900);
FORCEADD MOSFET_NCH_DUAL..1
(-1025 3425);
FORCEPROP 1 LAST LOCATION Q128
J 0
(-874 3399);
DISPLAY 0.723404 (-874 3399);
PAINT GREEN (-874 3399);
FORCEPROP 0 LAST $SEC 1
J 0
(-850 3550);
DISPLAY 0.680851 (-850 3550);
PAINT MONO (-850 3550);
DISPLAY INVISIBLE (-850 3550);
FORCEPROP 2 LAST CDS_SEC 1
J 0
(-850 3550);
DISPLAY 1.021277 (-850 3550);
DISPLAY INVISIBLE (-850 3550);
FORCEPROP 0 LASTPIN (-975 3625) $PN 6
R 1
J 0
(-985 3635);
DISPLAY 0.680851 (-985 3635);
PAINT MONO (-985 3635);
FORCEPROP 0 LASTPIN (-1225 3375) $PN 2
J 2
(-1235 3385);
DISPLAY 0.680851 (-1235 3385);
PAINT MONO (-1235 3385);
FORCEPROP 0 LASTPIN (-975 3225) $PN 1
R 1
J 2
(-985 3215);
DISPLAY 0.680851 (-985 3215);
PAINT MONO (-985 3215);
FORCEPROP 1 LAST MATERIAL IC
J 0
(-874 3274);
DISPLAY 0.723404 (-874 3274);
PAINT GREEN (-874 3274);
FORCEPROP 2 LAST VALUE PJT138K
J 0
(-850 3450);
DISPLAY 1.021277 (-850 3450);
FORCEPROP 2 LAST PART_TYPE SMLF
J 0
(-850 3500);
DISPLAY 1.021277 (-850 3500);
FORCEPROP 2 LAST CDS_LIB pure_quanta
J 0
(-1025 3425);
DISPLAY INVISIBLE (-1025 3425);
FORCEPROP 1 LAST NEEDS_NO_SIZE TRUE
J 0
(-1025 3424);
DISPLAY 0.468085 (-1025 3424);
PAINT GREEN (-1025 3424);
DISPLAY INVISIBLE (-1025 3424);
FORCEPROP 1 LAST CDS_LMAN_SYM_OUTLINE -150,150,150,-150
J 0
(-1025 3425);
DISPLAY 0.468085 (-1025 3425);
PAINT GREEN (-1025 3425);
DISPLAY INVISIBLE (-1025 3425);
FORCEPROP 1 LAST PATH I37
J 0
(-1025 3425);
DISPLAY 0.723404 (-1025 3425);
PAINT GREEN (-1025 3425);
DISPLAY INVISIBLE (-1025 3425);
FORCEPROP 1 LAST PART_NUMBER BAM138K0003
J 0
(-874 3339);
DISPLAY 0.723404 (-874 3339);
PAINT GREEN (-874 3339);
DISPLAY INVISIBLE (-874 3339);
FORCEADD UNIVERSAL_GND..1
(-975 3050);
FORCEPROP 3 LASTPIN (-975 3100) SIG_NAME GND\g
J 0
(-965 3110);
DISPLAY 0.659574 (-965 3110);
PAINT MONO (-965 3110);
DISPLAY INVISIBLE (-965 3110);
FORCEPROP 2 LAST CDS_LIB pure_quanta_power
J 0
(-975 3050);
DISPLAY INVISIBLE (-975 3050);
FORCEPROP 1 LAST HDL_POWER GND
J 1
(-950 2975);
DISPLAY 0.872340 (-950 2975);
PAINT GREEN (-950 2975);
DISPLAY INVISIBLE (-950 2975);
FORCEPROP 1 LAST PATH I38
J 0
(-900 3050);
DISPLAY 0.872340 (-900 3050);
PAINT AQUA (-900 3050);
DISPLAY INVISIBLE (-900 3050);
FORCEADD Q_RES..2
(-975 4025);
FORCEPROP 1 LAST LOCATION R4125
J 0
(-930 4150);
DISPLAY 0.638298 (-930 4150);
FORCEPROP 2 LAST $SEC 1
J 0
(-925 4250);
DISPLAY 0.680851 (-925 4250);
PAINT MONO (-925 4250);
DISPLAY INVISIBLE (-925 4250);
FORCEPROP 2 LAST CDS_SEC 1
J 0
(-925 4250);
DISPLAY 1.021277 (-925 4250);
DISPLAY INVISIBLE (-925 4250);
FORCEPROP 1 LASTPIN (-975 4125) $PN 1
J 0
(-970 4087);
DISPLAY 0.787234 (-970 4087);
FORCEPROP 1 LASTPIN (-975 3925) $PN 2
J 0
(-970 3935);
DISPLAY 0.787234 (-970 3935);
FORCEPROP 1 LAST VALUE 4.7K
J 0
(-930 4100);
DISPLAY 0.638298 (-930 4100);
FORCEPROP 1 LAST TOLERANCE 5%
J 0
(-930 4050);
DISPLAY 0.638298 (-930 4050);
FORCEPROP 1 LAST WATTAGE 1/16W
J 0
(-935 4000);
DISPLAY 0.638298 (-935 4000);
FORCEPROP 1 LAST MATERIAL CHIP
J 0
(-935 3950);
DISPLAY 0.638298 (-935 3950);
FORCEPROP 1 LAST PACK_TYPE 0402LF
J 0
(-935 3900);
DISPLAY 0.638298 (-935 3900);
FORCEPROP 2 LAST CDS_LIB pure_quanta
J 0
(-975 4025);
PAINT MONO (-975 4025);
DISPLAY INVISIBLE (-975 4025);
FORCEPROP 1 LAST PATH I39
J 0
(-925 4200);
DISPLAY 0.978723 (-925 4200);
PAINT WHITE (-925 4200);
DISPLAY INVISIBLE (-925 4200);
FORCEPROP 1 LAST PART_NUMBER CS24702JB10
J 0
(-935 3850);
DISPLAY 0.638298 (-935 3850);
DISPLAY INVISIBLE (-935 3850);
FORCEADD Q_RES..2
(-2075 -725);
FORCEPROP 1 LAST LOCATION R4153
J 0
(-2030 -600);
DISPLAY 0.978723 (-2030 -600);
FORCEPROP 0 LAST $SEC 1
J 0
(-2025 -550);
DISPLAY 0.680851 (-2025 -550);
PAINT MONO (-2025 -550);
DISPLAY INVISIBLE (-2025 -550);
FORCEPROP 0 LAST CDS_SEC 1
J 0
(-2025 -550);
DISPLAY 0.680851 (-2025 -550);
DISPLAY INVISIBLE (-2025 -550);
FORCEPROP 1 LASTPIN (-2075 -625) $PN 1
J 0
(-2070 -663);
DISPLAY 0.787234 (-2070 -663);
PAINT MONO (-2070 -663);
FORCEPROP 1 LASTPIN (-2075 -825) $PN 2
J 0
(-2070 -815);
DISPLAY 0.787234 (-2070 -815);
PAINT MONO (-2070 -815);
FORCEPROP 1 LAST MATERIAL CHIP
J 0
(-2035 -800);
DISPLAY 0.978723 (-2035 -800);
FORCEPROP 1 LAST WATTAGE 1/16W
J 0
(-2035 -750);
DISPLAY 0.978723 (-2035 -750);
FORCEPROP 1 LAST TOLERANCE 1%
J 0
(-2030 -700);
DISPLAY 0.978723 (-2030 -700);
FORCEPROP 1 LAST VALUE 10K
J 0
(-2030 -650);
DISPLAY 0.978723 (-2030 -650);
FORCEPROP 1 LAST PACK_TYPE 0402LF
J 0
(-2035 -900);
DISPLAY 0.978723 (-2035 -900);
FORCEPROP 2 LAST CDS_LIB pure_quanta
J 0
(-2075 -725);
DISPLAY INVISIBLE (-2075 -725);
FORCEPROP 1 LAST PATH I4
J 0
(-2025 -550);
DISPLAY 0.978723 (-2025 -550);
PAINT WHITE (-2025 -550);
DISPLAY INVISIBLE (-2025 -550);
FORCEPROP 1 LAST PART_NUMBER CS31002FB08
J 0
(-2035 -850);
DISPLAY 0.978723 (-2035 -850);
DISPLAY INVISIBLE (-2035 -850);
FORCEADD MOSFET_NCH_DUAL..2
(150 2350);
FORCEPROP 1 LAST LOCATION Q131
J 0
(301 2326);
DISPLAY 0.723404 (301 2326);
PAINT GREEN (301 2326);
FORCEPROP 0 LAST $SEC 2
J 0
(325 2475);
DISPLAY 0.680851 (325 2475);
PAINT MONO (325 2475);
DISPLAY INVISIBLE (325 2475);
FORCEPROP 0 LAST CDS_SEC 2
J 0
(325 2475);
DISPLAY 1.021277 (325 2475);
DISPLAY INVISIBLE (325 2475);
FORCEPROP 0 LASTPIN (200 2550) $PN 3
R 1
J 0
(190 2560);
DISPLAY 0.680851 (190 2560);
PAINT MONO (190 2560);
FORCEPROP 0 LASTPIN (-50 2300) $PN 5
J 2
(-60 2310);
DISPLAY 0.680851 (-60 2310);
PAINT MONO (-60 2310);
FORCEPROP 0 LASTPIN (200 2150) $PN 4
R 1
J 2
(190 2140);
DISPLAY 0.680851 (190 2140);
PAINT MONO (190 2140);
FORCEPROP 2 LAST VALUE PJT138K
J 0
(325 2375);
DISPLAY 1.021277 (325 2375);
FORCEPROP 2 LAST PART_TYPE SMLF
J 0
(325 2425);
DISPLAY 1.021277 (325 2425);
FORCEPROP 1 LAST MATERIAL IC
J 0
(301 2201);
DISPLAY 0.723404 (301 2201);
PAINT GREEN (301 2201);
FORCEPROP 1 LAST CDS_LMAN_SYM_OUTLINE -150,150,150,-150
J 0
(150 2350);
DISPLAY 0.468085 (150 2350);
PAINT GREEN (150 2350);
DISPLAY INVISIBLE (150 2350);
FORCEPROP 1 LAST NEEDS_NO_SIZE TRUE
J 0
(300 2241);
DISPLAY 0.468085 (300 2241);
PAINT GREEN (300 2241);
DISPLAY INVISIBLE (300 2241);
FORCEPROP 2 LAST CDS_LIB pure_quanta
J 0
(150 2350);
DISPLAY INVISIBLE (150 2350);
FORCEPROP 1 LAST PATH I40
J 0
(300 2200);
DISPLAY 0.723404 (300 2200);
PAINT GREEN (300 2200);
DISPLAY INVISIBLE (300 2200);
FORCEPROP 1 LAST PART_NUMBER BAM138K0003
J 0
(301 2256);
DISPLAY 0.723404 (301 2256);
PAINT GREEN (301 2256);
DISPLAY INVISIBLE (301 2256);
FORCEADD Q_RES..1
(-700 3025);
FORCEPROP 1 LAST LOCATION R4572
J 0
(-950 3025);
DISPLAY 0.787234 (-950 3025);
FORCEPROP 0 LAST $SEC 1
J 0
(-450 3150);
DISPLAY 0.680851 (-450 3150);
PAINT MONO (-450 3150);
DISPLAY INVISIBLE (-450 3150);
FORCEPROP 0 LAST CDS_SEC 1
J 0
(-450 3150);
DISPLAY 1.021277 (-450 3150);
DISPLAY INVISIBLE (-450 3150);
FORCEPROP 1 LASTPIN (-800 3025) $PN 1
J 0
(-788 3037);
DISPLAY 0.787234 (-788 3037);
PAINT MONO (-788 3037);
FORCEPROP 1 LASTPIN (-600 3025) $PN 2
J 0
(-638 3037);
DISPLAY 0.787234 (-638 3037);
PAINT MONO (-638 3037);
FORCEPROP 1 LAST TOLERANCE 5%
J 0
(-550 3025);
DISPLAY 0.510638 (-550 3025);
FORCEPROP 1 LAST VALUE 0
J 2
(-575 3025);
DISPLAY 0.510638 (-575 3025);
FORCEPROP 1 LAST WATTAGE 1/16W
J 2
(-450 3125);
DISPLAY 0.510638 (-450 3125);
FORCEPROP 1 LAST MATERIAL EMPTY
J 0
(-475 3025);
DISPLAY 0.510638 (-475 3025);
PAINT RED (-475 3025);
FORCEPROP 1 LAST PACK_TYPE 0402LF
J 0
(-800 3125);
DISPLAY 0.510638 (-800 3125);
FORCEPROP 2 LAST CDS_LIB pure_quanta
J 0
(-700 3025);
DISPLAY INVISIBLE (-700 3025);
FORCEPROP 1 LAST PATH I41
J 0
(-750 3175);
DISPLAY 0.978723 (-750 3175);
PAINT WHITE (-750 3175);
DISPLAY INVISIBLE (-750 3175);
FORCEPROP 1 LAST PART_NUMBER CS00002JB13
J 0
(-750 3075);
DISPLAY 0.510638 (-750 3075);
DISPLAY INVISIBLE (-750 3075);
FORCEADD MOSFET_NCH_DUAL..2
(125 3725);
FORCEPROP 1 LAST LOCATION Q128
J 0
(276 3701);
DISPLAY 0.723404 (276 3701);
PAINT GREEN (276 3701);
FORCEPROP 0 LAST $SEC 2
J 0
(300 3850);
DISPLAY 0.680851 (300 3850);
PAINT MONO (300 3850);
DISPLAY INVISIBLE (300 3850);
FORCEPROP 0 LAST CDS_SEC 2
J 0
(300 3850);
DISPLAY 1.021277 (300 3850);
DISPLAY INVISIBLE (300 3850);
FORCEPROP 0 LASTPIN (175 3925) $PN 3
R 1
J 0
(165 3935);
DISPLAY 0.680851 (165 3935);
PAINT MONO (165 3935);
FORCEPROP 0 LASTPIN (-75 3675) $PN 5
J 2
(-85 3685);
DISPLAY 0.680851 (-85 3685);
PAINT MONO (-85 3685);
FORCEPROP 0 LASTPIN (175 3525) $PN 4
R 1
J 2
(165 3515);
DISPLAY 0.680851 (165 3515);
PAINT MONO (165 3515);
FORCEPROP 2 LAST PART_TYPE SMLF
J 0
(300 3800);
DISPLAY 1.021277 (300 3800);
FORCEPROP 2 LAST VALUE PJT138K
J 0
(300 3750);
DISPLAY 1.021277 (300 3750);
FORCEPROP 1 LAST MATERIAL IC
J 0
(276 3576);
DISPLAY 0.723404 (276 3576);
PAINT GREEN (276 3576);
FORCEPROP 2 LAST CDS_LIB pure_quanta
J 0
(125 3725);
DISPLAY INVISIBLE (125 3725);
FORCEPROP 1 LAST NEEDS_NO_SIZE TRUE
J 0
(275 3616);
DISPLAY 0.468085 (275 3616);
PAINT GREEN (275 3616);
DISPLAY INVISIBLE (275 3616);
FORCEPROP 1 LAST CDS_LMAN_SYM_OUTLINE -150,150,150,-150
J 0
(125 3725);
DISPLAY 0.468085 (125 3725);
PAINT GREEN (125 3725);
DISPLAY INVISIBLE (125 3725);
FORCEPROP 1 LAST PATH I42
J 0
(275 3575);
DISPLAY 0.723404 (275 3575);
PAINT GREEN (275 3575);
DISPLAY INVISIBLE (275 3575);
FORCEPROP 1 LAST PART_NUMBER BAM138K0003
J 0
(276 3631);
DISPLAY 0.723404 (276 3631);
PAINT GREEN (276 3631);
DISPLAY INVISIBLE (276 3631);
FORCEADD UNIVERSAL_POWER..1
(-975 4250);
FORCEPROP 3 LASTPIN (-975 4200) SIG_NAME P3V3_AUX\g
J 0
(-965 4210);
DISPLAY 0.659574 (-965 4210);
PAINT MONO (-965 4210);
DISPLAY INVISIBLE (-965 4210);
FORCEPROP 1 LAST HDL_POWER P3V3_AUX
J 1
(-975 4300);
DISPLAY 0.872340 (-975 4300);
PAINT GREEN (-975 4300);
FORCEPROP 2 LAST CDS_LIB pure_quanta_power
J 0
(-975 4250);
PAINT MONO (-975 4250);
DISPLAY INVISIBLE (-975 4250);
FORCEPROP 1 LAST PATH I43
J 0
(-925 4275);
DISPLAY 0.872340 (-925 4275);
PAINT AQUA (-925 4275);
DISPLAY INVISIBLE (-925 4275);
FORCEADD Q_RES..1
(-575 4475);
FORCEPROP 1 LAST LOCATION R4575
J 0
(-850 4475);
DISPLAY 0.787234 (-850 4475);
FORCEPROP 0 LAST $SEC 1
J 0
(-325 4600);
DISPLAY 0.680851 (-325 4600);
PAINT MONO (-325 4600);
DISPLAY INVISIBLE (-325 4600);
FORCEPROP 0 LAST CDS_SEC 1
J 0
(-325 4600);
DISPLAY 1.021277 (-325 4600);
DISPLAY INVISIBLE (-325 4600);
FORCEPROP 1 LASTPIN (-675 4475) $PN 1
J 0
(-663 4487);
DISPLAY 0.787234 (-663 4487);
PAINT MONO (-663 4487);
FORCEPROP 1 LASTPIN (-475 4475) $PN 2
J 0
(-513 4487);
DISPLAY 0.787234 (-513 4487);
PAINT MONO (-513 4487);
FORCEPROP 1 LAST PACK_TYPE 0402LF
J 0
(-675 4575);
DISPLAY 0.510638 (-675 4575);
FORCEPROP 1 LAST VALUE 0
J 2
(-450 4475);
DISPLAY 0.510638 (-450 4475);
FORCEPROP 1 LAST MATERIAL EMPTY
J 0
(-350 4475);
DISPLAY 0.510638 (-350 4475);
PAINT RED (-350 4475);
FORCEPROP 1 LAST TOLERANCE 5%
J 0
(-425 4475);
DISPLAY 0.510638 (-425 4475);
FORCEPROP 1 LAST WATTAGE 1/16W
J 2
(-325 4575);
DISPLAY 0.510638 (-325 4575);
FORCEPROP 2 LAST CDS_LIB pure_quanta
J 0
(-575 4475);
DISPLAY INVISIBLE (-575 4475);
FORCEPROP 1 LAST PATH I44
J 0
(-625 4625);
DISPLAY 0.978723 (-625 4625);
PAINT WHITE (-625 4625);
DISPLAY INVISIBLE (-625 4625);
FORCEPROP 1 LAST PART_NUMBER CS00002JB13
J 0
(-625 4525);
DISPLAY 0.510638 (-625 4525);
DISPLAY INVISIBLE (-625 4525);
FORCEADD UNIVERSAL_GND..1
(175 3350);
FORCEPROP 3 LASTPIN (175 3400) SIG_NAME GND\g
J 0
(185 3410);
DISPLAY 0.659574 (185 3410);
PAINT MONO (185 3410);
DISPLAY INVISIBLE (185 3410);
FORCEPROP 2 LAST CDS_LIB pure_quanta_power
J 0
(175 3350);
DISPLAY INVISIBLE (175 3350);
FORCEPROP 1 LAST HDL_POWER GND
J 1
(200 3275);
DISPLAY 0.872340 (200 3275);
PAINT GREEN (200 3275);
DISPLAY INVISIBLE (200 3275);
FORCEPROP 1 LAST PATH I45
J 0
(250 3350);
DISPLAY 0.872340 (250 3350);
PAINT AQUA (250 3350);
DISPLAY INVISIBLE (250 3350);
FORCEADD UNIVERSAL_GND..1
(175 525);
FORCEPROP 3 LASTPIN (175 575) SIG_NAME GND\g
J 0
(185 585);
DISPLAY 0.659574 (185 585);
PAINT MONO (185 585);
DISPLAY INVISIBLE (185 585);
FORCEPROP 2 LAST CDS_LIB pure_quanta_power
J 0
(175 525);
DISPLAY INVISIBLE (175 525);
FORCEPROP 1 LAST HDL_POWER GND
J 1
(200 450);
DISPLAY 0.872340 (200 450);
PAINT GREEN (200 450);
DISPLAY INVISIBLE (200 450);
FORCEPROP 1 LAST PATH I46
J 0
(250 525);
DISPLAY 0.872340 (250 525);
PAINT AQUA (250 525);
DISPLAY INVISIBLE (250 525);
FORCEADD UNIVERSAL_GND..1
(250 -1025);
FORCEPROP 3 LASTPIN (250 -975) SIG_NAME GND\g
J 0
(260 -965);
DISPLAY 0.659574 (260 -965);
PAINT MONO (260 -965);
DISPLAY INVISIBLE (260 -965);
FORCEPROP 2 LAST CDS_LIB pure_quanta_power
J 0
(250 -1025);
DISPLAY INVISIBLE (250 -1025);
FORCEPROP 1 LAST HDL_POWER GND
J 1
(275 -1100);
DISPLAY 0.872340 (275 -1100);
PAINT GREEN (275 -1100);
DISPLAY INVISIBLE (275 -1100);
FORCEPROP 1 LAST PATH I47
J 0
(325 -1025);
DISPLAY 0.872340 (325 -1025);
PAINT AQUA (325 -1025);
DISPLAY INVISIBLE (325 -1025);
FORCEADD Q_RES..2
(250 -225);
FORCEPROP 1 LAST LOCATION R4156
J 0
(295 -100);
DISPLAY 0.638298 (295 -100);
FORCEPROP 2 LAST $SEC 1
J 0
(300 0);
DISPLAY 0.680851 (300 0);
PAINT MONO (300 0);
DISPLAY INVISIBLE (300 0);
FORCEPROP 2 LAST CDS_SEC 1
J 0
(300 0);
DISPLAY 1.021277 (300 0);
DISPLAY INVISIBLE (300 0);
FORCEPROP 1 LASTPIN (250 -125) $PN 1
J 0
(255 -163);
DISPLAY 0.787234 (255 -163);
FORCEPROP 1 LASTPIN (250 -325) $PN 2
J 0
(255 -315);
DISPLAY 0.787234 (255 -315);
FORCEPROP 1 LAST VALUE 100K
J 0
(295 -150);
DISPLAY 0.638298 (295 -150);
FORCEPROP 1 LAST TOLERANCE 1%
J 0
(295 -200);
DISPLAY 0.638298 (295 -200);
FORCEPROP 1 LAST PACK_TYPE 0402LF
J 0
(290 -350);
DISPLAY 0.638298 (290 -350);
FORCEPROP 1 LAST WATTAGE 1/16W
J 0
(290 -250);
DISPLAY 0.638298 (290 -250);
FORCEPROP 1 LAST MATERIAL CHIP
J 0
(290 -300);
DISPLAY 0.638298 (290 -300);
FORCEPROP 2 LAST CDS_LIB pure_quanta
J 0
(250 -225);
PAINT MONO (250 -225);
DISPLAY INVISIBLE (250 -225);
FORCEPROP 1 LAST PATH I48
J 0
(300 -50);
DISPLAY 0.978723 (300 -50);
PAINT WHITE (300 -50);
DISPLAY INVISIBLE (300 -50);
FORCEPROP 1 LAST PART_NUMBER CS41002FB09
J 0
(290 -400);
DISPLAY 0.638298 (290 -400);
DISPLAY INVISIBLE (290 -400);
FORCEADD UNIVERSAL_GND..1
(1025 -900);
FORCEPROP 3 LASTPIN (1025 -850) SIG_NAME GND\g
J 0
(1035 -840);
DISPLAY 0.659574 (1035 -840);
PAINT MONO (1035 -840);
DISPLAY INVISIBLE (1035 -840);
FORCEPROP 2 LAST CDS_LIB pure_quanta_power
J 0
(1025 -900);
DISPLAY INVISIBLE (1025 -900);
FORCEPROP 1 LAST HDL_POWER GND
J 1
(1050 -975);
DISPLAY 0.872340 (1050 -975);
PAINT GREEN (1050 -975);
DISPLAY INVISIBLE (1050 -975);
FORCEPROP 1 LAST PATH I49
J 0
(1100 -900);
DISPLAY 0.872340 (1100 -900);
PAINT AQUA (1100 -900);
DISPLAY INVISIBLE (1100 -900);
FORCEADD UNIVERSAL_POWER..1
(-2075 -475);
FORCEPROP 3 LASTPIN (-2075 -525) SIG_NAME P3V3_AUX\g
J 0
(-2065 -515);
DISPLAY 0.659574 (-2065 -515);
PAINT MONO (-2065 -515);
DISPLAY INVISIBLE (-2065 -515);
FORCEPROP 1 LAST HDL_POWER P3V3_AUX
J 1
(-2075 -425);
DISPLAY 0.872340 (-2075 -425);
PAINT GREEN (-2075 -425);
FORCEPROP 2 LAST CDS_LIB pure_quanta_power
J 0
(-2075 -475);
PAINT MONO (-2075 -475);
DISPLAY INVISIBLE (-2075 -475);
FORCEPROP 1 LAST PATH I5
J 0
(-2025 -450);
DISPLAY 0.872340 (-2025 -450);
PAINT AQUA (-2025 -450);
DISPLAY INVISIBLE (-2025 -450);
FORCEADD Q_CAP..1
(1025 -700);
FORCEPROP 1 LAST LOCATION C15
J 0
(1075 -600);
DISPLAY 0.978723 (1075 -600);
FORCEPROP 0 LAST $SEC 1
J 0
(1075 -550);
DISPLAY 0.680851 (1075 -550);
PAINT MONO (1075 -550);
DISPLAY INVISIBLE (1075 -550);
FORCEPROP 0 LAST CDS_SEC 1
J 0
(1075 -550);
DISPLAY 1.021277 (1075 -550);
DISPLAY INVISIBLE (1075 -550);
FORCEPROP 1 LASTPIN (1025 -600) $PN 1
J 0
(1035 -620);
DISPLAY 0.787234 (1035 -620);
PAINT MONO (1035 -620);
FORCEPROP 1 LASTPIN (1025 -800) $PN 2
J 0
(1035 -820);
DISPLAY 0.787234 (1035 -820);
PAINT MONO (1035 -820);
FORCEPROP 1 LAST MATERIAL X7R
J 0
(1075 -800);
DISPLAY 0.638298 (1075 -800);
PAINT RED (1075 -800);
FORCEPROP 1 LAST VALUE 0.1UF
J 0
(1075 -650);
DISPLAY 0.638298 (1075 -650);
FORCEPROP 1 LAST VOLTAGE 25V
J 0
(1075 -700);
DISPLAY 0.638298 (1075 -700);
FORCEPROP 1 LAST TOLERANCE 10%
J 0
(1075 -750);
DISPLAY 0.638298 (1075 -750);
FORCEPROP 1 LAST PACK_TYPE 0402
J 0
(1075 -900);
DISPLAY 0.638298 (1075 -900);
FORCEPROP 2 LAST CDS_LIB pure_quanta
J 0
(1025 -700);
DISPLAY INVISIBLE (1025 -700);
FORCEPROP 1 LAST PATH I50
J 0
(1075 -550);
DISPLAY 0.978723 (1075 -550);
PAINT WHITE (1075 -550);
DISPLAY INVISIBLE (1075 -550);
FORCEPROP 1 LAST PART_NUMBER CH4104K1B00
J 0
(1075 -850);
DISPLAY 0.638298 (1075 -850);
DISPLAY INVISIBLE (1075 -850);
FORCEADD OFFPAGE..2
(1375 -400);
FORCEPROP 2 LAST $XR1 246 
J 0
(1654 -400);
DISPLAY 0.638298 (1654 -400);
PAINT MONO (1654 -400);
FORCEPROP 2 LAST $XR0 81 
J 0
(1564 -400);
DISPLAY 0.638298 (1564 -400);
PAINT MONO (1564 -400);
FORCEPROP 2 LAST CDS_LIB standard
J 0
(1375 -400);
DISPLAY INVISIBLE (1375 -400);
FORCEPROP 1 LAST OFFPAGE TRUE
J 0
(1700 -525);
DISPLAY 0.872340 (1700 -525);
PAINT AQUA (1700 -525);
DISPLAY INVISIBLE (1700 -525);
FORCEPROP 1 LAST COMMENT_BODY TRUE
J 0
(1330 -495);
DISPLAY 0.872340 (1330 -495);
PAINT GREEN (1330 -495);
DISPLAY INVISIBLE (1330 -495);
FORCEPROP 2 LAST PATH I51
J 0
(1675 -350);
DISPLAY 0.680851 (1675 -350);
DISPLAY INVISIBLE (1675 -350);
FORCEADD OFFPAGE..4
R 2
(2225 -625);
FORCEPROP 2 LAST $XR0 117 
J 0
(1973 -625);
DISPLAY 0.638298 (1973 -625);
PAINT MONO (1973 -625);
FORCEPROP 2 LAST CDS_LIB standard
J 0
(2225 -625);
DISPLAY INVISIBLE (2225 -625);
FORCEPROP 1 LAST OFFPAGE TRUE
J 2
(1900 -750);
DISPLAY 0.872340 (1900 -750);
PAINT GREEN (1900 -750);
DISPLAY INVISIBLE (1900 -750);
FORCEPROP 1 LAST COMMENT_BODY TRUE
J 2
(2250 -725);
DISPLAY 0.872340 (2250 -725);
PAINT GREEN (2250 -725);
DISPLAY INVISIBLE (2250 -725);
FORCEPROP 2 LAST PATH I52
J 0
(1950 -575);
DISPLAY 0.680851 (1950 -575);
DISPLAY INVISIBLE (1950 -575);
FORCEADD UNIVERSAL_GND..1
(2500 -1100);
FORCEPROP 3 LASTPIN (2500 -1050) SIG_NAME GND\g
J 0
(2510 -1040);
DISPLAY 0.659574 (2510 -1040);
PAINT MONO (2510 -1040);
DISPLAY INVISIBLE (2510 -1040);
FORCEPROP 2 LAST CDS_LIB pure_quanta_power
J 0
(2500 -1100);
DISPLAY INVISIBLE (2500 -1100);
FORCEPROP 1 LAST HDL_POWER GND
J 1
(2525 -1175);
DISPLAY 0.872340 (2525 -1175);
PAINT GREEN (2525 -1175);
DISPLAY INVISIBLE (2525 -1175);
FORCEPROP 1 LAST PATH I53
J 0
(2575 -1100);
DISPLAY 0.872340 (2575 -1100);
PAINT AQUA (2575 -1100);
DISPLAY INVISIBLE (2575 -1100);
FORCEADD Q_RES..2
(2500 -825);
FORCEPROP 1 LAST LOCATION R4559
J 0
(2545 -700);
DISPLAY 0.978723 (2545 -700);
FORCEPROP 0 LAST $SEC 1
J 0
(2550 -650);
DISPLAY 0.680851 (2550 -650);
PAINT MONO (2550 -650);
DISPLAY INVISIBLE (2550 -650);
FORCEPROP 0 LAST CDS_SEC 1
J 0
(2550 -650);
DISPLAY 1.021277 (2550 -650);
DISPLAY INVISIBLE (2550 -650);
FORCEPROP 1 LASTPIN (2500 -725) $PN 1
J 0
(2505 -763);
DISPLAY 0.787234 (2505 -763);
PAINT MONO (2505 -763);
FORCEPROP 1 LASTPIN (2500 -925) $PN 2
J 0
(2505 -915);
DISPLAY 0.787234 (2505 -915);
PAINT MONO (2505 -915);
FORCEPROP 1 LAST TOLERANCE 1%
J 0
(2545 -800);
DISPLAY 0.510638 (2545 -800);
FORCEPROP 1 LAST PACK_TYPE 0402LF
J 0
(2540 -1000);
DISPLAY 0.510638 (2540 -1000);
FORCEPROP 1 LAST VALUE 100K
J 0
(2545 -750);
DISPLAY 0.510638 (2545 -750);
FORCEPROP 1 LAST WATTAGE 1/16W
J 0
(2540 -850);
DISPLAY 0.510638 (2540 -850);
FORCEPROP 1 LAST MATERIAL CHIP
J 0
(2540 -900);
DISPLAY 0.510638 (2540 -900);
FORCEPROP 2 LAST CDS_LIB pure_quanta
J 0
(2500 -825);
DISPLAY INVISIBLE (2500 -825);
FORCEPROP 1 LAST PATH I54
J 0
(2550 -650);
DISPLAY 0.978723 (2550 -650);
PAINT WHITE (2550 -650);
DISPLAY INVISIBLE (2550 -650);
FORCEPROP 1 LAST PART_NUMBER CS41002FB09
J 0
(2540 -950);
DISPLAY 0.510638 (2540 -950);
DISPLAY INVISIBLE (2540 -950);
FORCEADD Q_RES..2
(2475 -350);
FORCEPROP 1 LAST LOCATION R4562
J 0
(2520 -225);
DISPLAY 0.978723 (2520 -225);
FORCEPROP 0 LAST $SEC 1
J 0
(2525 -175);
DISPLAY 0.680851 (2525 -175);
PAINT MONO (2525 -175);
DISPLAY INVISIBLE (2525 -175);
FORCEPROP 0 LAST CDS_SEC 1
J 0
(2525 -175);
DISPLAY 1.021277 (2525 -175);
DISPLAY INVISIBLE (2525 -175);
FORCEPROP 1 LASTPIN (2475 -250) $PN 1
J 0
(2480 -288);
DISPLAY 0.787234 (2480 -288);
PAINT MONO (2480 -288);
FORCEPROP 1 LASTPIN (2475 -450) $PN 2
J 0
(2480 -440);
DISPLAY 0.787234 (2480 -440);
PAINT MONO (2480 -440);
FORCEPROP 1 LAST PACK_TYPE 0402LF
J 0
(2515 -525);
DISPLAY 0.510638 (2515 -525);
FORCEPROP 1 LAST VALUE 100K
J 0
(2520 -275);
DISPLAY 0.510638 (2520 -275);
FORCEPROP 1 LAST WATTAGE 1/16W
J 0
(2515 -375);
DISPLAY 0.510638 (2515 -375);
FORCEPROP 1 LAST TOLERANCE 1%
J 0
(2520 -325);
DISPLAY 0.510638 (2520 -325);
FORCEPROP 1 LAST MATERIAL EMPTY
J 0
(2515 -425);
DISPLAY 0.510638 (2515 -425);
PAINT RED (2515 -425);
FORCEPROP 2 LAST CDS_LIB pure_quanta
J 0
(2475 -350);
DISPLAY INVISIBLE (2475 -350);
FORCEPROP 1 LAST PATH I55
J 0
(2525 -175);
DISPLAY 0.978723 (2525 -175);
PAINT WHITE (2525 -175);
DISPLAY INVISIBLE (2525 -175);
FORCEPROP 1 LAST PART_NUMBER CS41002FB09
J 0
(2515 -475);
DISPLAY 0.510638 (2515 -475);
DISPLAY INVISIBLE (2515 -475);
FORCEADD UNIVERSAL_POWER..1
(2475 -100);
FORCEPROP 3 LASTPIN (2475 -150) SIG_NAME P3V3_AUX\g
J 0
(2485 -140);
DISPLAY 0.659574 (2485 -140);
PAINT MONO (2485 -140);
DISPLAY INVISIBLE (2485 -140);
FORCEPROP 1 LAST HDL_POWER P3V3_AUX
J 1
(2475 -50);
DISPLAY 0.872340 (2475 -50);
PAINT GREEN (2475 -50);
FORCEPROP 2 LAST CDS_LIB pure_quanta_power
J 0
(2475 -100);
PAINT MONO (2475 -100);
DISPLAY INVISIBLE (2475 -100);
FORCEPROP 1 LAST PATH I56
J 0
(2525 -75);
DISPLAY 0.872340 (2525 -75);
PAINT AQUA (2525 -75);
DISPLAY INVISIBLE (2525 -75);
FORCEADD MOSFET_NCH_DUAL..1
(3600 -575);
FORCEPROP 1 LAST LOCATION Q146
J 0
(3751 -601);
DISPLAY 0.723404 (3751 -601);
PAINT GREEN (3751 -601);
FORCEPROP 0 LAST $SEC 1
J 0
(3775 -450);
DISPLAY 0.680851 (3775 -450);
PAINT MONO (3775 -450);
DISPLAY INVISIBLE (3775 -450);
FORCEPROP 2 LAST CDS_SEC 1
J 0
(3775 -450);
DISPLAY 1.021277 (3775 -450);
DISPLAY INVISIBLE (3775 -450);
FORCEPROP 0 LASTPIN (3650 -375) $PN 6
R 1
J 0
(3640 -365);
DISPLAY 0.680851 (3640 -365);
PAINT MONO (3640 -365);
FORCEPROP 0 LASTPIN (3400 -625) $PN 2
J 2
(3390 -615);
DISPLAY 0.680851 (3390 -615);
PAINT MONO (3390 -615);
FORCEPROP 0 LASTPIN (3650 -775) $PN 1
R 1
J 2
(3640 -785);
DISPLAY 0.680851 (3640 -785);
PAINT MONO (3640 -785);
FORCEPROP 2 LAST VALUE PJT138K
J 0
(3775 -550);
DISPLAY 1.021277 (3775 -550);
FORCEPROP 1 LAST MATERIAL IC
J 0
(3751 -726);
DISPLAY 0.723404 (3751 -726);
PAINT GREEN (3751 -726);
FORCEPROP 2 LAST PART_TYPE SMLF
J 0
(3775 -500);
DISPLAY 1.021277 (3775 -500);
FORCEPROP 1 LAST CDS_LMAN_SYM_OUTLINE -150,150,150,-150
J 0
(3600 -575);
DISPLAY 0.468085 (3600 -575);
PAINT GREEN (3600 -575);
DISPLAY INVISIBLE (3600 -575);
FORCEPROP 1 LAST NEEDS_NO_SIZE TRUE
J 0
(3600 -576);
DISPLAY 0.468085 (3600 -576);
PAINT GREEN (3600 -576);
DISPLAY INVISIBLE (3600 -576);
FORCEPROP 2 LAST CDS_LIB pure_quanta
J 0
(3600 -575);
DISPLAY INVISIBLE (3600 -575);
FORCEPROP 1 LAST PATH I57
J 0
(3600 -575);
DISPLAY 0.723404 (3600 -575);
PAINT GREEN (3600 -575);
DISPLAY INVISIBLE (3600 -575);
FORCEPROP 1 LAST PART_NUMBER BAM138K0003
J 0
(3751 -661);
DISPLAY 0.723404 (3751 -661);
PAINT GREEN (3751 -661);
DISPLAY INVISIBLE (3751 -661);
FORCEADD UNIVERSAL_GND..1
(3650 -950);
FORCEPROP 3 LASTPIN (3650 -900) SIG_NAME GND\g
J 0
(3660 -890);
DISPLAY 0.659574 (3660 -890);
PAINT MONO (3660 -890);
DISPLAY INVISIBLE (3660 -890);
FORCEPROP 2 LAST CDS_LIB pure_quanta_power
J 0
(3650 -950);
DISPLAY INVISIBLE (3650 -950);
FORCEPROP 1 LAST HDL_POWER GND
J 1
(3675 -1025);
DISPLAY 0.872340 (3675 -1025);
PAINT GREEN (3675 -1025);
DISPLAY INVISIBLE (3675 -1025);
FORCEPROP 1 LAST PATH I58
J 0
(3725 -950);
DISPLAY 0.872340 (3725 -950);
PAINT AQUA (3725 -950);
DISPLAY INVISIBLE (3725 -950);
FORCEADD UNIVERSAL_GND..1
(4800 -650);
FORCEPROP 3 LASTPIN (4800 -600) SIG_NAME GND\g
J 0
(4810 -590);
DISPLAY 0.659574 (4810 -590);
PAINT MONO (4810 -590);
DISPLAY INVISIBLE (4810 -590);
FORCEPROP 2 LAST CDS_LIB pure_quanta_power
J 0
(4800 -650);
DISPLAY INVISIBLE (4800 -650);
FORCEPROP 1 LAST HDL_POWER GND
J 1
(4825 -725);
DISPLAY 0.872340 (4825 -725);
PAINT GREEN (4825 -725);
DISPLAY INVISIBLE (4825 -725);
FORCEPROP 1 LAST PATH I59
J 0
(4875 -650);
DISPLAY 0.872340 (4875 -650);
PAINT AQUA (4875 -650);
DISPLAY INVISIBLE (4875 -650);
FORCEADD MOSFET_NCH_DUAL..1
(-950 -950);
FORCEPROP 1 LAST LOCATION Q134
J 0
(-799 -976);
DISPLAY 0.723404 (-799 -976);
PAINT GREEN (-799 -976);
FORCEPROP 0 LAST $SEC 1
J 0
(-775 -825);
DISPLAY 0.680851 (-775 -825);
PAINT MONO (-775 -825);
DISPLAY INVISIBLE (-775 -825);
FORCEPROP 2 LAST CDS_SEC 1
J 0
(-775 -825);
DISPLAY 1.021277 (-775 -825);
DISPLAY INVISIBLE (-775 -825);
FORCEPROP 0 LASTPIN (-900 -750) $PN 6
R 1
J 0
(-910 -740);
DISPLAY 0.680851 (-910 -740);
PAINT MONO (-910 -740);
FORCEPROP 0 LASTPIN (-1150 -1000) $PN 2
J 2
(-1160 -990);
DISPLAY 0.680851 (-1160 -990);
PAINT MONO (-1160 -990);
FORCEPROP 0 LASTPIN (-900 -1150) $PN 1
R 1
J 2
(-910 -1160);
DISPLAY 0.680851 (-910 -1160);
PAINT MONO (-910 -1160);
FORCEPROP 2 LAST VALUE PJT138K
J 0
(-775 -925);
DISPLAY 1.021277 (-775 -925);
FORCEPROP 2 LAST PART_TYPE SMLF
J 0
(-775 -875);
DISPLAY 1.021277 (-775 -875);
FORCEPROP 1 LAST MATERIAL IC
J 0
(-799 -1101);
DISPLAY 0.723404 (-799 -1101);
PAINT GREEN (-799 -1101);
FORCEPROP 2 LAST CDS_LIB pure_quanta
J 0
(-950 -950);
DISPLAY INVISIBLE (-950 -950);
FORCEPROP 1 LAST NEEDS_NO_SIZE TRUE
J 0
(-950 -951);
DISPLAY 0.468085 (-950 -951);
PAINT GREEN (-950 -951);
DISPLAY INVISIBLE (-950 -951);
FORCEPROP 1 LAST CDS_LMAN_SYM_OUTLINE -150,150,150,-150
J 0
(-950 -950);
DISPLAY 0.468085 (-950 -950);
PAINT GREEN (-950 -950);
DISPLAY INVISIBLE (-950 -950);
FORCEPROP 1 LAST PATH I6
J 0
(-950 -950);
DISPLAY 0.723404 (-950 -950);
PAINT GREEN (-950 -950);
DISPLAY INVISIBLE (-950 -950);
FORCEPROP 1 LAST PART_NUMBER BAM138K0003
J 0
(-799 -1036);
DISPLAY 0.723404 (-799 -1036);
PAINT GREEN (-799 -1036);
DISPLAY INVISIBLE (-799 -1036);
FORCEADD UNIVERSAL_GND..1
(5575 -525);
FORCEPROP 3 LASTPIN (5575 -475) SIG_NAME GND\g
J 0
(5585 -465);
DISPLAY 0.659574 (5585 -465);
PAINT MONO (5585 -465);
DISPLAY INVISIBLE (5585 -465);
FORCEPROP 2 LAST CDS_LIB pure_quanta_power
J 0
(5575 -525);
DISPLAY INVISIBLE (5575 -525);
FORCEPROP 1 LAST HDL_POWER GND
J 1
(5600 -600);
DISPLAY 0.872340 (5600 -600);
PAINT GREEN (5600 -600);
DISPLAY INVISIBLE (5600 -600);
FORCEPROP 1 LAST PATH I60
J 0
(5650 -525);
DISPLAY 0.872340 (5650 -525);
PAINT AQUA (5650 -525);
DISPLAY INVISIBLE (5650 -525);
FORCEADD Q_CAP..1
(5575 -325);
FORCEPROP 1 LAST LOCATION C18
J 0
(5625 -225);
DISPLAY 0.978723 (5625 -225);
FORCEPROP 0 LAST $SEC 1
J 0
(5625 -175);
DISPLAY 0.680851 (5625 -175);
PAINT MONO (5625 -175);
DISPLAY INVISIBLE (5625 -175);
FORCEPROP 0 LAST CDS_SEC 1
J 0
(5625 -175);
DISPLAY 1.021277 (5625 -175);
DISPLAY INVISIBLE (5625 -175);
FORCEPROP 1 LASTPIN (5575 -225) $PN 1
J 0
(5585 -245);
DISPLAY 0.787234 (5585 -245);
PAINT MONO (5585 -245);
FORCEPROP 1 LASTPIN (5575 -425) $PN 2
J 0
(5585 -445);
DISPLAY 0.787234 (5585 -445);
PAINT MONO (5585 -445);
FORCEPROP 1 LAST VALUE 0.1UF
J 0
(5625 -275);
DISPLAY 0.638298 (5625 -275);
FORCEPROP 1 LAST VOLTAGE 25V
J 0
(5625 -325);
DISPLAY 0.638298 (5625 -325);
FORCEPROP 1 LAST TOLERANCE 10%
J 0
(5625 -375);
DISPLAY 0.638298 (5625 -375);
FORCEPROP 1 LAST MATERIAL X7R
J 0
(5625 -425);
DISPLAY 0.638298 (5625 -425);
PAINT RED (5625 -425);
FORCEPROP 1 LAST PACK_TYPE 0402
J 0
(5625 -525);
DISPLAY 0.638298 (5625 -525);
FORCEPROP 2 LAST CDS_LIB pure_quanta
J 0
(5575 -325);
DISPLAY INVISIBLE (5575 -325);
FORCEPROP 1 LAST PATH I61
J 0
(5625 -175);
DISPLAY 0.978723 (5625 -175);
PAINT WHITE (5625 -175);
DISPLAY INVISIBLE (5625 -175);
FORCEPROP 1 LAST PART_NUMBER CH4104K1B00
J 0
(5625 -475);
DISPLAY 0.638298 (5625 -475);
DISPLAY INVISIBLE (5625 -475);
FORCEADD Q_RES..2
(3650 25);
FORCEPROP 1 LAST LOCATION R4560
J 0
(3695 150);
DISPLAY 0.638298 (3695 150);
FORCEPROP 2 LAST $SEC 1
J 0
(3700 250);
DISPLAY 0.680851 (3700 250);
PAINT MONO (3700 250);
DISPLAY INVISIBLE (3700 250);
FORCEPROP 2 LAST CDS_SEC 1
J 0
(3700 250);
DISPLAY 1.021277 (3700 250);
DISPLAY INVISIBLE (3700 250);
FORCEPROP 1 LASTPIN (3650 125) $PN 1
J 0
(3655 87);
DISPLAY 0.787234 (3655 87);
FORCEPROP 1 LASTPIN (3650 -75) $PN 2
J 0
(3655 -65);
DISPLAY 0.787234 (3655 -65);
FORCEPROP 1 LAST WATTAGE 1/16W
J 0
(3690 0);
DISPLAY 0.638298 (3690 0);
FORCEPROP 1 LAST PACK_TYPE 0402LF
J 0
(3690 -100);
DISPLAY 0.638298 (3690 -100);
FORCEPROP 1 LAST TOLERANCE 5%
J 0
(3695 50);
DISPLAY 0.638298 (3695 50);
FORCEPROP 1 LAST MATERIAL CHIP
J 0
(3690 -50);
DISPLAY 0.638298 (3690 -50);
FORCEPROP 1 LAST VALUE 4.7K
J 0
(3695 100);
DISPLAY 0.638298 (3695 100);
FORCEPROP 2 LAST CDS_LIB pure_quanta
J 0
(3650 25);
PAINT MONO (3650 25);
DISPLAY INVISIBLE (3650 25);
FORCEPROP 1 LAST PATH I62
J 0
(3700 200);
DISPLAY 0.978723 (3700 200);
PAINT WHITE (3700 200);
DISPLAY INVISIBLE (3700 200);
FORCEPROP 1 LAST PART_NUMBER CS24702JB10
J 0
(3690 -150);
DISPLAY 0.638298 (3690 -150);
DISPLAY INVISIBLE (3690 -150);
FORCEADD UNIVERSAL_POWER..1
(250 0);
FORCEPROP 3 LASTPIN (250 -50) SIG_NAME P3V3_AUX\g
J 0
(260 -40);
DISPLAY 0.659574 (260 -40);
PAINT MONO (260 -40);
DISPLAY INVISIBLE (260 -40);
FORCEPROP 1 LAST HDL_POWER P3V3_AUX
J 1
(250 50);
DISPLAY 0.872340 (250 50);
PAINT GREEN (250 50);
FORCEPROP 2 LAST CDS_LIB pure_quanta_power
J 0
(250 0);
PAINT MONO (250 0);
DISPLAY INVISIBLE (250 0);
FORCEPROP 1 LAST PATH I63
J 0
(300 25);
DISPLAY 0.872340 (300 25);
PAINT AQUA (300 25);
DISPLAY INVISIBLE (300 25);
FORCEADD Q_CAP..1
(950 850);
FORCEPROP 1 LAST LOCATION C13
J 0
(1000 950);
DISPLAY 0.978723 (1000 950);
FORCEPROP 0 LAST $SEC 1
J 0
(1000 1000);
DISPLAY 0.680851 (1000 1000);
PAINT MONO (1000 1000);
DISPLAY INVISIBLE (1000 1000);
FORCEPROP 0 LAST CDS_SEC 1
J 0
(1000 1000);
DISPLAY 1.021277 (1000 1000);
DISPLAY INVISIBLE (1000 1000);
FORCEPROP 1 LASTPIN (950 950) $PN 1
J 0
(960 930);
DISPLAY 0.787234 (960 930);
PAINT MONO (960 930);
FORCEPROP 1 LASTPIN (950 750) $PN 2
J 0
(960 730);
DISPLAY 0.787234 (960 730);
PAINT MONO (960 730);
FORCEPROP 1 LAST TOLERANCE 10%
J 0
(1000 800);
DISPLAY 0.638298 (1000 800);
FORCEPROP 1 LAST MATERIAL X7R
J 0
(1000 750);
DISPLAY 0.638298 (1000 750);
PAINT RED (1000 750);
FORCEPROP 1 LAST PACK_TYPE 0402
J 0
(1000 650);
DISPLAY 0.638298 (1000 650);
FORCEPROP 1 LAST VOLTAGE 25V
J 0
(1000 850);
DISPLAY 0.638298 (1000 850);
FORCEPROP 1 LAST VALUE 0.1UF
J 0
(1000 900);
DISPLAY 0.638298 (1000 900);
FORCEPROP 2 LAST CDS_LIB pure_quanta
J 0
(950 850);
DISPLAY INVISIBLE (950 850);
FORCEPROP 1 LAST PATH I64
J 0
(1000 1000);
DISPLAY 0.978723 (1000 1000);
PAINT WHITE (1000 1000);
DISPLAY INVISIBLE (1000 1000);
FORCEPROP 1 LAST PART_NUMBER CH4104K1B00
J 0
(1000 700);
DISPLAY 0.638298 (1000 700);
DISPLAY INVISIBLE (1000 700);
FORCEADD UNIVERSAL_GND..1
(950 650);
FORCEPROP 3 LASTPIN (950 700) SIG_NAME GND\g
J 0
(960 710);
DISPLAY 0.659574 (960 710);
PAINT MONO (960 710);
DISPLAY INVISIBLE (960 710);
FORCEPROP 2 LAST CDS_LIB pure_quanta_power
J 0
(950 650);
DISPLAY INVISIBLE (950 650);
FORCEPROP 1 LAST HDL_POWER GND
J 1
(975 575);
DISPLAY 0.872340 (975 575);
PAINT GREEN (975 575);
DISPLAY INVISIBLE (975 575);
FORCEPROP 1 LAST PATH I65
J 0
(1025 650);
DISPLAY 0.872340 (1025 650);
PAINT AQUA (1025 650);
DISPLAY INVISIBLE (1025 650);
FORCEADD Q_RES..2
(175 1325);
FORCEPROP 1 LAST LOCATION R4129
J 0
(220 1450);
DISPLAY 0.638298 (220 1450);
FORCEPROP 2 LAST $SEC 1
J 0
(225 1550);
DISPLAY 0.680851 (225 1550);
PAINT MONO (225 1550);
DISPLAY INVISIBLE (225 1550);
FORCEPROP 2 LAST CDS_SEC 1
J 0
(225 1550);
DISPLAY 1.021277 (225 1550);
DISPLAY INVISIBLE (225 1550);
FORCEPROP 1 LASTPIN (175 1425) $PN 1
J 0
(180 1387);
DISPLAY 0.787234 (180 1387);
FORCEPROP 1 LASTPIN (175 1225) $PN 2
J 0
(180 1235);
DISPLAY 0.787234 (180 1235);
FORCEPROP 1 LAST TOLERANCE 1%
J 0
(220 1350);
DISPLAY 0.638298 (220 1350);
FORCEPROP 1 LAST VALUE 100K
J 0
(220 1400);
DISPLAY 0.638298 (220 1400);
FORCEPROP 1 LAST MATERIAL CHIP
J 0
(215 1250);
DISPLAY 0.638298 (215 1250);
FORCEPROP 1 LAST WATTAGE 1/16W
J 0
(215 1300);
DISPLAY 0.638298 (215 1300);
FORCEPROP 1 LAST PACK_TYPE 0402LF
J 0
(215 1200);
DISPLAY 0.638298 (215 1200);
FORCEPROP 2 LAST CDS_LIB pure_quanta
J 0
(175 1325);
PAINT MONO (175 1325);
DISPLAY INVISIBLE (175 1325);
FORCEPROP 1 LAST PATH I66
J 0
(225 1500);
DISPLAY 0.978723 (225 1500);
PAINT WHITE (225 1500);
DISPLAY INVISIBLE (225 1500);
FORCEPROP 1 LAST PART_NUMBER CS41002FB09
J 0
(215 1150);
DISPLAY 0.638298 (215 1150);
DISPLAY INVISIBLE (215 1150);
FORCEADD UNIVERSAL_GND..1
(200 1975);
FORCEPROP 3 LASTPIN (200 2025) SIG_NAME GND\g
J 0
(210 2035);
DISPLAY 0.659574 (210 2035);
PAINT MONO (210 2035);
DISPLAY INVISIBLE (210 2035);
FORCEPROP 2 LAST CDS_LIB pure_quanta_power
J 0
(200 1975);
DISPLAY INVISIBLE (200 1975);
FORCEPROP 1 LAST HDL_POWER GND
J 1
(225 1900);
DISPLAY 0.872340 (225 1900);
PAINT GREEN (225 1900);
DISPLAY INVISIBLE (225 1900);
FORCEPROP 1 LAST PATH I67
J 0
(275 1975);
DISPLAY 0.872340 (275 1975);
PAINT AQUA (275 1975);
DISPLAY INVISIBLE (275 1975);
FORCEADD OFFPAGE..4
R 2
(2225 850);
FORCEPROP 2 LAST $XR0 118 
J 0
(1973 850);
DISPLAY 0.638298 (1973 850);
PAINT MONO (1973 850);
FORCEPROP 2 LAST CDS_LIB standard
J 0
(2225 850);
DISPLAY INVISIBLE (2225 850);
FORCEPROP 1 LAST OFFPAGE TRUE
J 2
(1900 725);
DISPLAY 0.872340 (1900 725);
PAINT GREEN (1900 725);
DISPLAY INVISIBLE (1900 725);
FORCEPROP 1 LAST COMMENT_BODY TRUE
J 2
(2250 750);
DISPLAY 0.872340 (2250 750);
PAINT GREEN (2250 750);
DISPLAY INVISIBLE (2250 750);
FORCEPROP 2 LAST PATH I68
J 0
(1950 900);
DISPLAY 0.680851 (1950 900);
DISPLAY INVISIBLE (1950 900);
FORCEADD OFFPAGE..2
(1300 1150);
FORCEPROP 2 LAST $XR1 246 
J 0
(1579 1150);
DISPLAY 0.638298 (1579 1150);
PAINT MONO (1579 1150);
FORCEPROP 2 LAST $XR0 80 
J 0
(1489 1150);
DISPLAY 0.638298 (1489 1150);
PAINT MONO (1489 1150);
FORCEPROP 2 LAST CDS_LIB standard
J 0
(1300 1150);
DISPLAY INVISIBLE (1300 1150);
FORCEPROP 1 LAST OFFPAGE TRUE
J 0
(1625 1025);
DISPLAY 0.872340 (1625 1025);
PAINT AQUA (1625 1025);
DISPLAY INVISIBLE (1625 1025);
FORCEPROP 1 LAST COMMENT_BODY TRUE
J 0
(1255 1055);
DISPLAY 0.872340 (1255 1055);
PAINT GREEN (1255 1055);
DISPLAY INVISIBLE (1255 1055);
FORCEPROP 2 LAST PATH I69
J 0
(1600 1200);
DISPLAY 0.680851 (1600 1200);
DISPLAY INVISIBLE (1600 1200);
FORCEADD UNIVERSAL_GND..1
(-900 -1325);
FORCEPROP 3 LASTPIN (-900 -1275) SIG_NAME GND\g
J 0
(-890 -1265);
DISPLAY 0.659574 (-890 -1265);
PAINT MONO (-890 -1265);
DISPLAY INVISIBLE (-890 -1265);
FORCEPROP 2 LAST CDS_LIB pure_quanta_power
J 0
(-900 -1325);
DISPLAY INVISIBLE (-900 -1325);
FORCEPROP 1 LAST HDL_POWER GND
J 1
(-875 -1400);
DISPLAY 0.872340 (-875 -1400);
PAINT GREEN (-875 -1400);
DISPLAY INVISIBLE (-875 -1400);
FORCEPROP 1 LAST PATH I7
J 0
(-825 -1325);
DISPLAY 0.872340 (-825 -1325);
PAINT AQUA (-825 -1325);
DISPLAY INVISIBLE (-825 -1325);
FORCEADD Q_RES..2
(200 2775);
FORCEPROP 1 LAST LOCATION R4130
J 0
(245 2900);
DISPLAY 0.638298 (245 2900);
FORCEPROP 2 LAST $SEC 1
J 0
(250 3000);
DISPLAY 0.680851 (250 3000);
PAINT MONO (250 3000);
DISPLAY INVISIBLE (250 3000);
FORCEPROP 2 LAST CDS_SEC 1
J 0
(250 3000);
DISPLAY 1.021277 (250 3000);
DISPLAY INVISIBLE (250 3000);
FORCEPROP 1 LASTPIN (200 2875) $PN 1
J 0
(205 2837);
DISPLAY 0.787234 (205 2837);
FORCEPROP 1 LASTPIN (200 2675) $PN 2
J 0
(205 2685);
DISPLAY 0.787234 (205 2685);
FORCEPROP 1 LAST MATERIAL CHIP
J 0
(240 2700);
DISPLAY 0.638298 (240 2700);
FORCEPROP 1 LAST PACK_TYPE 0402LF
J 0
(240 2650);
DISPLAY 0.638298 (240 2650);
FORCEPROP 1 LAST WATTAGE 1/16W
J 0
(240 2750);
DISPLAY 0.638298 (240 2750);
FORCEPROP 1 LAST VALUE 100K
J 0
(245 2850);
DISPLAY 0.638298 (245 2850);
FORCEPROP 1 LAST TOLERANCE 1%
J 0
(245 2800);
DISPLAY 0.638298 (245 2800);
FORCEPROP 2 LAST CDS_LIB pure_quanta
J 0
(200 2775);
PAINT MONO (200 2775);
DISPLAY INVISIBLE (200 2775);
FORCEPROP 1 LAST PATH I70
J 0
(250 2950);
DISPLAY 0.978723 (250 2950);
PAINT WHITE (250 2950);
DISPLAY INVISIBLE (250 2950);
FORCEPROP 1 LAST PART_NUMBER CS41002FB09
J 0
(240 2600);
DISPLAY 0.638298 (240 2600);
DISPLAY INVISIBLE (240 2600);
FORCEADD UNIVERSAL_POWER..1
(200 3000);
FORCEPROP 3 LASTPIN (200 2950) SIG_NAME P3V3_AUX\g
J 0
(210 2960);
DISPLAY 0.659574 (210 2960);
PAINT MONO (210 2960);
DISPLAY INVISIBLE (210 2960);
FORCEPROP 1 LAST HDL_POWER P3V3_AUX
J 1
(200 3050);
DISPLAY 0.872340 (200 3050);
PAINT GREEN (200 3050);
FORCEPROP 2 LAST CDS_LIB pure_quanta_power
J 0
(200 3000);
PAINT MONO (200 3000);
DISPLAY INVISIBLE (200 3000);
FORCEPROP 1 LAST PATH I71
J 0
(250 3025);
DISPLAY 0.872340 (250 3025);
PAINT AQUA (250 3025);
DISPLAY INVISIBLE (250 3025);
FORCEADD UNIVERSAL_GND..1
(975 2100);
FORCEPROP 3 LASTPIN (975 2150) SIG_NAME GND\g
J 0
(985 2160);
DISPLAY 0.659574 (985 2160);
PAINT MONO (985 2160);
DISPLAY INVISIBLE (985 2160);
FORCEPROP 2 LAST CDS_LIB pure_quanta_power
J 0
(975 2100);
DISPLAY INVISIBLE (975 2100);
FORCEPROP 1 LAST HDL_POWER GND
J 1
(1000 2025);
DISPLAY 0.872340 (1000 2025);
PAINT GREEN (1000 2025);
DISPLAY INVISIBLE (1000 2025);
FORCEPROP 1 LAST PATH I72
J 0
(1050 2100);
DISPLAY 0.872340 (1050 2100);
PAINT AQUA (1050 2100);
DISPLAY INVISIBLE (1050 2100);
FORCEADD Q_CAP..1
(975 2300);
FORCEPROP 1 LAST LOCATION C14
J 0
(1025 2400);
DISPLAY 0.978723 (1025 2400);
FORCEPROP 0 LAST $SEC 1
J 0
(1025 2450);
DISPLAY 0.680851 (1025 2450);
PAINT MONO (1025 2450);
DISPLAY INVISIBLE (1025 2450);
FORCEPROP 0 LAST CDS_SEC 1
J 0
(1025 2450);
DISPLAY 1.021277 (1025 2450);
DISPLAY INVISIBLE (1025 2450);
FORCEPROP 1 LASTPIN (975 2400) $PN 1
J 0
(985 2380);
DISPLAY 0.787234 (985 2380);
PAINT MONO (985 2380);
FORCEPROP 1 LASTPIN (975 2200) $PN 2
J 0
(985 2180);
DISPLAY 0.787234 (985 2180);
PAINT MONO (985 2180);
FORCEPROP 1 LAST MATERIAL X7R
J 0
(1025 2200);
DISPLAY 0.638298 (1025 2200);
PAINT RED (1025 2200);
FORCEPROP 1 LAST TOLERANCE 10%
J 0
(1025 2250);
DISPLAY 0.638298 (1025 2250);
FORCEPROP 1 LAST VOLTAGE 25V
J 0
(1025 2300);
DISPLAY 0.638298 (1025 2300);
FORCEPROP 1 LAST PACK_TYPE 0402
J 0
(1025 2100);
DISPLAY 0.638298 (1025 2100);
FORCEPROP 1 LAST VALUE 0.1UF
J 0
(1025 2350);
DISPLAY 0.638298 (1025 2350);
FORCEPROP 2 LAST CDS_LIB pure_quanta
J 0
(975 2300);
DISPLAY INVISIBLE (975 2300);
FORCEPROP 1 LAST PATH I73
J 0
(1025 2450);
DISPLAY 0.978723 (1025 2450);
PAINT WHITE (1025 2450);
DISPLAY INVISIBLE (1025 2450);
FORCEPROP 1 LAST PART_NUMBER CH4104K1B00
J 0
(1025 2150);
DISPLAY 0.638298 (1025 2150);
DISPLAY INVISIBLE (1025 2150);
FORCEADD UNIVERSAL_GND..1
(950 3475);
FORCEPROP 3 LASTPIN (950 3525) SIG_NAME GND\g
J 0
(960 3535);
DISPLAY 0.659574 (960 3535);
PAINT MONO (960 3535);
DISPLAY INVISIBLE (960 3535);
FORCEPROP 2 LAST CDS_LIB pure_quanta_power
J 0
(950 3475);
DISPLAY INVISIBLE (950 3475);
FORCEPROP 1 LAST HDL_POWER GND
J 1
(975 3400);
DISPLAY 0.872340 (975 3400);
PAINT GREEN (975 3400);
DISPLAY INVISIBLE (975 3400);
FORCEPROP 1 LAST PATH I74
J 0
(1025 3475);
DISPLAY 0.872340 (1025 3475);
PAINT AQUA (1025 3475);
DISPLAY INVISIBLE (1025 3475);
FORCEADD Q_CAP..1
(950 3675);
FORCEPROP 1 LAST LOCATION C12
J 0
(1000 3775);
DISPLAY 0.978723 (1000 3775);
FORCEPROP 0 LAST $SEC 1
J 0
(1000 3825);
DISPLAY 0.680851 (1000 3825);
PAINT MONO (1000 3825);
DISPLAY INVISIBLE (1000 3825);
FORCEPROP 0 LAST CDS_SEC 1
J 0
(1000 3825);
DISPLAY 1.021277 (1000 3825);
DISPLAY INVISIBLE (1000 3825);
FORCEPROP 1 LASTPIN (950 3775) $PN 1
J 0
(960 3755);
DISPLAY 0.787234 (960 3755);
PAINT MONO (960 3755);
FORCEPROP 1 LASTPIN (950 3575) $PN 2
J 0
(960 3555);
DISPLAY 0.787234 (960 3555);
PAINT MONO (960 3555);
FORCEPROP 1 LAST VALUE 0.1UF
J 0
(1000 3725);
DISPLAY 0.638298 (1000 3725);
FORCEPROP 1 LAST TOLERANCE 10%
J 0
(1000 3625);
DISPLAY 0.638298 (1000 3625);
FORCEPROP 1 LAST MATERIAL X7R
J 0
(1000 3575);
DISPLAY 0.638298 (1000 3575);
PAINT RED (1000 3575);
FORCEPROP 1 LAST VOLTAGE 25V
J 0
(1000 3675);
DISPLAY 0.638298 (1000 3675);
FORCEPROP 1 LAST PACK_TYPE 0402
J 0
(1000 3475);
DISPLAY 0.638298 (1000 3475);
FORCEPROP 2 LAST CDS_LIB pure_quanta
J 0
(950 3675);
DISPLAY INVISIBLE (950 3675);
FORCEPROP 1 LAST PATH I75
J 0
(1000 3825);
DISPLAY 0.978723 (1000 3825);
PAINT WHITE (1000 3825);
DISPLAY INVISIBLE (1000 3825);
FORCEPROP 1 LAST PART_NUMBER CH4104K1B00
J 0
(1000 3525);
DISPLAY 0.638298 (1000 3525);
DISPLAY INVISIBLE (1000 3525);
FORCEADD OFFPAGE..2
(1325 2600);
FORCEPROP 2 LAST $XR0 81 
J 0
(1514 2600);
DISPLAY 0.638298 (1514 2600);
PAINT MONO (1514 2600);
FORCEPROP 2 LAST CDS_LIB standard
J 0
(1325 2600);
DISPLAY INVISIBLE (1325 2600);
FORCEPROP 1 LAST OFFPAGE TRUE
J 0
(1650 2475);
DISPLAY 0.872340 (1650 2475);
PAINT AQUA (1650 2475);
DISPLAY INVISIBLE (1650 2475);
FORCEPROP 1 LAST COMMENT_BODY TRUE
J 0
(1280 2505);
DISPLAY 0.872340 (1280 2505);
PAINT GREEN (1280 2505);
DISPLAY INVISIBLE (1280 2505);
FORCEPROP 2 LAST PATH I76
J 0
(1525 2650);
DISPLAY 0.680851 (1525 2650);
DISPLAY INVISIBLE (1525 2650);
FORCEADD OFFPAGE..4
R 2
(2250 2300);
FORCEPROP 2 LAST $XR0 118 
J 0
(1998 2300);
DISPLAY 0.638298 (1998 2300);
PAINT MONO (1998 2300);
FORCEPROP 2 LAST CDS_LIB standard
J 0
(2250 2300);
DISPLAY INVISIBLE (2250 2300);
FORCEPROP 1 LAST OFFPAGE TRUE
J 2
(1925 2175);
DISPLAY 0.872340 (1925 2175);
PAINT GREEN (1925 2175);
DISPLAY INVISIBLE (1925 2175);
FORCEPROP 1 LAST COMMENT_BODY TRUE
J 2
(2275 2200);
DISPLAY 0.872340 (2275 2200);
PAINT GREEN (2275 2200);
DISPLAY INVISIBLE (2275 2200);
FORCEPROP 2 LAST PATH I77
J 0
(2000 2350);
DISPLAY 0.680851 (2000 2350);
DISPLAY INVISIBLE (2000 2350);
FORCEADD OFFPAGE..2
(1300 3975);
FORCEPROP 2 LAST $XR0 81 
J 0
(1489 3975);
DISPLAY 0.638298 (1489 3975);
PAINT MONO (1489 3975);
FORCEPROP 2 LAST CDS_LIB standard
J 0
(1300 3975);
DISPLAY INVISIBLE (1300 3975);
FORCEPROP 1 LAST OFFPAGE TRUE
J 0
(1625 3850);
DISPLAY 0.872340 (1625 3850);
PAINT AQUA (1625 3850);
DISPLAY INVISIBLE (1625 3850);
FORCEPROP 1 LAST COMMENT_BODY TRUE
J 0
(1255 3880);
DISPLAY 0.872340 (1255 3880);
PAINT GREEN (1255 3880);
DISPLAY INVISIBLE (1255 3880);
FORCEPROP 2 LAST PATH I78
J 0
(1500 4025);
DISPLAY 0.680851 (1500 4025);
DISPLAY INVISIBLE (1500 4025);
FORCEADD OFFPAGE..4
R 2
(2225 3675);
FORCEPROP 2 LAST $XR0 118 
J 0
(1973 3675);
DISPLAY 0.638298 (1973 3675);
PAINT MONO (1973 3675);
FORCEPROP 2 LAST CDS_LIB standard
J 0
(2225 3675);
DISPLAY INVISIBLE (2225 3675);
FORCEPROP 1 LAST OFFPAGE TRUE
J 2
(1900 3550);
DISPLAY 0.872340 (1900 3550);
PAINT GREEN (1900 3550);
DISPLAY INVISIBLE (1900 3550);
FORCEPROP 1 LAST COMMENT_BODY TRUE
J 2
(2250 3575);
DISPLAY 0.872340 (2250 3575);
PAINT GREEN (2250 3575);
DISPLAY INVISIBLE (2250 3575);
FORCEPROP 2 LAST PATH I79
J 0
(1950 3725);
DISPLAY 0.680851 (1950 3725);
DISPLAY INVISIBLE (1950 3725);
FORCEADD Q_RES..2
(-900 -350);
FORCEPROP 1 LAST LOCATION R4155
J 0
(-855 -225);
DISPLAY 0.638298 (-855 -225);
FORCEPROP 2 LAST $SEC 1
J 0
(-850 -125);
DISPLAY 0.680851 (-850 -125);
PAINT MONO (-850 -125);
DISPLAY INVISIBLE (-850 -125);
FORCEPROP 2 LAST CDS_SEC 1
J 0
(-850 -125);
DISPLAY 1.021277 (-850 -125);
DISPLAY INVISIBLE (-850 -125);
FORCEPROP 1 LASTPIN (-900 -250) $PN 1
J 0
(-895 -288);
DISPLAY 0.787234 (-895 -288);
FORCEPROP 1 LASTPIN (-900 -450) $PN 2
J 0
(-895 -440);
DISPLAY 0.787234 (-895 -440);
FORCEPROP 1 LAST MATERIAL CHIP
J 0
(-860 -425);
DISPLAY 0.638298 (-860 -425);
FORCEPROP 1 LAST PACK_TYPE 0402LF
J 0
(-860 -475);
DISPLAY 0.638298 (-860 -475);
FORCEPROP 1 LAST WATTAGE 1/16W
J 0
(-860 -375);
DISPLAY 0.638298 (-860 -375);
FORCEPROP 1 LAST TOLERANCE 5%
J 0
(-855 -325);
DISPLAY 0.638298 (-855 -325);
FORCEPROP 1 LAST VALUE 4.7K
J 0
(-855 -275);
DISPLAY 0.638298 (-855 -275);
FORCEPROP 2 LAST CDS_LIB pure_quanta
J 0
(-900 -350);
PAINT MONO (-900 -350);
DISPLAY INVISIBLE (-900 -350);
FORCEPROP 1 LAST PATH I8
J 0
(-850 -175);
DISPLAY 0.978723 (-850 -175);
PAINT WHITE (-850 -175);
DISPLAY INVISIBLE (-850 -175);
FORCEPROP 1 LAST PART_NUMBER CS24702JB10
J 0
(-860 -525);
DISPLAY 0.638298 (-860 -525);
DISPLAY INVISIBLE (-860 -525);
FORCEADD UNIVERSAL_GND..1
(2500 375);
FORCEPROP 3 LASTPIN (2500 425) SIG_NAME GND\g
J 0
(2510 435);
DISPLAY 0.659574 (2510 435);
PAINT MONO (2510 435);
DISPLAY INVISIBLE (2510 435);
FORCEPROP 2 LAST CDS_LIB pure_quanta_power
J 0
(2500 375);
DISPLAY INVISIBLE (2500 375);
FORCEPROP 1 LAST HDL_POWER GND
J 1
(2525 300);
DISPLAY 0.872340 (2525 300);
PAINT GREEN (2525 300);
DISPLAY INVISIBLE (2525 300);
FORCEPROP 1 LAST PATH I80
J 0
(2575 375);
DISPLAY 0.872340 (2575 375);
PAINT AQUA (2575 375);
DISPLAY INVISIBLE (2575 375);
FORCEADD Q_RES..2
(2500 650);
FORCEPROP 1 LAST LOCATION R4134
J 0
(2545 775);
DISPLAY 0.978723 (2545 775);
FORCEPROP 0 LAST $SEC 1
J 0
(2550 825);
DISPLAY 0.680851 (2550 825);
PAINT MONO (2550 825);
DISPLAY INVISIBLE (2550 825);
FORCEPROP 0 LAST CDS_SEC 1
J 0
(2550 825);
DISPLAY 1.021277 (2550 825);
DISPLAY INVISIBLE (2550 825);
FORCEPROP 1 LASTPIN (2500 750) $PN 1
J 0
(2505 712);
DISPLAY 0.787234 (2505 712);
PAINT MONO (2505 712);
FORCEPROP 1 LASTPIN (2500 550) $PN 2
J 0
(2505 560);
DISPLAY 0.787234 (2505 560);
PAINT MONO (2505 560);
FORCEPROP 1 LAST PACK_TYPE 0402LF
J 0
(2540 475);
DISPLAY 0.510638 (2540 475);
FORCEPROP 1 LAST TOLERANCE 1%
J 0
(2545 675);
DISPLAY 0.510638 (2545 675);
FORCEPROP 1 LAST MATERIAL EMPTY
J 0
(2540 575);
DISPLAY 0.510638 (2540 575);
PAINT RED (2540 575);
FORCEPROP 1 LAST WATTAGE 1/16W
J 0
(2540 625);
DISPLAY 0.510638 (2540 625);
FORCEPROP 1 LAST VALUE 100K
J 0
(2545 725);
DISPLAY 0.510638 (2545 725);
FORCEPROP 2 LAST CDS_LIB pure_quanta
J 0
(2500 650);
DISPLAY INVISIBLE (2500 650);
FORCEPROP 1 LAST PATH I81
J 0
(2550 825);
DISPLAY 0.978723 (2550 825);
PAINT WHITE (2550 825);
DISPLAY INVISIBLE (2550 825);
FORCEPROP 1 LAST PART_NUMBER CS41002FB09
J 0
(2540 525);
DISPLAY 0.510638 (2540 525);
DISPLAY INVISIBLE (2540 525);
FORCEADD Q_RES..2
(2475 1125);
FORCEPROP 1 LAST LOCATION R4133
J 0
(2520 1250);
DISPLAY 0.978723 (2520 1250);
FORCEPROP 0 LAST $SEC 1
J 0
(2525 1300);
DISPLAY 0.680851 (2525 1300);
PAINT MONO (2525 1300);
DISPLAY INVISIBLE (2525 1300);
FORCEPROP 0 LAST CDS_SEC 1
J 0
(2525 1300);
DISPLAY 1.021277 (2525 1300);
DISPLAY INVISIBLE (2525 1300);
FORCEPROP 1 LASTPIN (2475 1225) $PN 1
J 0
(2480 1187);
DISPLAY 0.787234 (2480 1187);
PAINT MONO (2480 1187);
FORCEPROP 1 LASTPIN (2475 1025) $PN 2
J 0
(2480 1035);
DISPLAY 0.787234 (2480 1035);
PAINT MONO (2480 1035);
FORCEPROP 1 LAST VALUE 54.9K
J 0
(2520 1200);
DISPLAY 0.787234 (2520 1200);
FORCEPROP 1 LAST TOLERANCE 1%
J 0
(2520 1150);
DISPLAY 0.787234 (2520 1150);
FORCEPROP 1 LAST WATTAGE 1/16W
J 0
(2515 1100);
DISPLAY 0.787234 (2515 1100);
FORCEPROP 1 LAST PACK_TYPE 0402LF
J 0
(2515 950);
DISPLAY 0.787234 (2515 950);
FORCEPROP 1 LAST MATERIAL EMPTY
J 0
(2515 1050);
DISPLAY 0.787234 (2515 1050);
PAINT RED (2515 1050);
FORCEPROP 2 LAST CDS_LIB pure_quanta
J 0
(2475 1125);
DISPLAY INVISIBLE (2475 1125);
FORCEPROP 1 LAST PATH I82
J 0
(2525 1300);
DISPLAY 0.978723 (2525 1300);
PAINT WHITE (2525 1300);
DISPLAY INVISIBLE (2525 1300);
FORCEPROP 1 LAST PART_NUMBER CS35492FB03
J 0
(2515 1000);
DISPLAY 0.787234 (2515 1000);
DISPLAY INVISIBLE (2515 1000);
FORCEADD UNIVERSAL_POWER..1
(2475 1375);
FORCEPROP 3 LASTPIN (2475 1325) SIG_NAME P3V3_AUX\g
J 0
(2485 1335);
DISPLAY 0.659574 (2485 1335);
PAINT MONO (2485 1335);
DISPLAY INVISIBLE (2485 1335);
FORCEPROP 1 LAST HDL_POWER P3V3_AUX
J 1
(2475 1425);
DISPLAY 0.872340 (2475 1425);
PAINT GREEN (2475 1425);
FORCEPROP 2 LAST CDS_LIB pure_quanta_power
J 0
(2475 1375);
PAINT MONO (2475 1375);
DISPLAY INVISIBLE (2475 1375);
FORCEPROP 1 LAST PATH I83
J 0
(2525 1400);
DISPLAY 0.872340 (2525 1400);
PAINT AQUA (2525 1400);
DISPLAY INVISIBLE (2525 1400);
FORCEADD UNIVERSAL_GND..1
(2525 1825);
FORCEPROP 3 LASTPIN (2525 1875) SIG_NAME GND\g
J 0
(2535 1885);
DISPLAY 0.659574 (2535 1885);
PAINT MONO (2535 1885);
DISPLAY INVISIBLE (2535 1885);
FORCEPROP 2 LAST CDS_LIB pure_quanta_power
J 0
(2525 1825);
DISPLAY INVISIBLE (2525 1825);
FORCEPROP 1 LAST HDL_POWER GND
J 1
(2550 1750);
DISPLAY 0.872340 (2550 1750);
PAINT GREEN (2550 1750);
DISPLAY INVISIBLE (2550 1750);
FORCEPROP 1 LAST PATH I84
J 0
(2600 1825);
DISPLAY 0.872340 (2600 1825);
PAINT AQUA (2600 1825);
DISPLAY INVISIBLE (2600 1825);
FORCEADD UNIVERSAL_POWER..1
(3650 250);
FORCEPROP 3 LASTPIN (3650 200) SIG_NAME P3V3_AUX\g
J 0
(3660 210);
DISPLAY 0.659574 (3660 210);
PAINT MONO (3660 210);
DISPLAY INVISIBLE (3660 210);
FORCEPROP 1 LAST HDL_POWER P3V3_AUX
J 1
(3650 300);
DISPLAY 0.872340 (3650 300);
PAINT GREEN (3650 300);
FORCEPROP 2 LAST CDS_LIB pure_quanta_power
J 0
(3650 250);
PAINT MONO (3650 250);
DISPLAY INVISIBLE (3650 250);
FORCEPROP 1 LAST PATH I85
J 0
(3700 275);
DISPLAY 0.872340 (3700 275);
PAINT AQUA (3700 275);
DISPLAY INVISIBLE (3700 275);
FORCEADD MOSFET_NCH_DUAL..1
(3600 900);
FORCEPROP 1 LAST LOCATION Q129
J 0
(3751 874);
DISPLAY 0.723404 (3751 874);
PAINT GREEN (3751 874);
FORCEPROP 0 LAST $SEC 1
J 0
(3775 1025);
DISPLAY 0.680851 (3775 1025);
PAINT MONO (3775 1025);
DISPLAY INVISIBLE (3775 1025);
FORCEPROP 2 LAST CDS_SEC 1
J 0
(3775 1025);
DISPLAY 1.021277 (3775 1025);
DISPLAY INVISIBLE (3775 1025);
FORCEPROP 0 LASTPIN (3650 1100) $PN 6
R 1
J 0
(3640 1110);
DISPLAY 0.680851 (3640 1110);
PAINT MONO (3640 1110);
FORCEPROP 0 LASTPIN (3400 850) $PN 2
J 2
(3390 860);
DISPLAY 0.680851 (3390 860);
PAINT MONO (3390 860);
FORCEPROP 0 LASTPIN (3650 700) $PN 1
R 1
J 2
(3640 690);
DISPLAY 0.680851 (3640 690);
PAINT MONO (3640 690);
FORCEPROP 2 LAST PART_TYPE SMLF
J 0
(3775 975);
DISPLAY 1.021277 (3775 975);
FORCEPROP 2 LAST VALUE PJT138K
J 0
(3775 925);
DISPLAY 1.021277 (3775 925);
FORCEPROP 1 LAST MATERIAL IC
J 0
(3751 749);
DISPLAY 0.723404 (3751 749);
PAINT GREEN (3751 749);
FORCEPROP 1 LAST CDS_LMAN_SYM_OUTLINE -150,150,150,-150
J 0
(3600 900);
DISPLAY 0.468085 (3600 900);
PAINT GREEN (3600 900);
DISPLAY INVISIBLE (3600 900);
FORCEPROP 1 LAST NEEDS_NO_SIZE TRUE
J 0
(3600 899);
DISPLAY 0.468085 (3600 899);
PAINT GREEN (3600 899);
DISPLAY INVISIBLE (3600 899);
FORCEPROP 2 LAST CDS_LIB pure_quanta
J 0
(3600 900);
DISPLAY INVISIBLE (3600 900);
FORCEPROP 1 LAST PATH I86
J 0
(3600 900);
DISPLAY 0.723404 (3600 900);
PAINT GREEN (3600 900);
DISPLAY INVISIBLE (3600 900);
FORCEPROP 1 LAST PART_NUMBER BAM138K0003
J 0
(3751 814);
DISPLAY 0.723404 (3751 814);
PAINT GREEN (3751 814);
DISPLAY INVISIBLE (3751 814);
FORCEADD UNIVERSAL_GND..1
(3650 525);
FORCEPROP 3 LASTPIN (3650 575) SIG_NAME GND\g
J 0
(3660 585);
DISPLAY 0.659574 (3660 585);
PAINT MONO (3660 585);
DISPLAY INVISIBLE (3660 585);
FORCEPROP 2 LAST CDS_LIB pure_quanta_power
J 0
(3650 525);
DISPLAY INVISIBLE (3650 525);
FORCEPROP 1 LAST HDL_POWER GND
J 1
(3675 450);
DISPLAY 0.872340 (3675 450);
PAINT GREEN (3675 450);
DISPLAY INVISIBLE (3675 450);
FORCEPROP 1 LAST PATH I87
J 0
(3725 525);
DISPLAY 0.872340 (3725 525);
PAINT AQUA (3725 525);
DISPLAY INVISIBLE (3725 525);
FORCEADD Q_RES..2
(3650 1500);
FORCEPROP 1 LAST LOCATION R4138
J 0
(3695 1625);
DISPLAY 0.638298 (3695 1625);
FORCEPROP 2 LAST $SEC 1
J 0
(3700 1725);
DISPLAY 0.680851 (3700 1725);
PAINT MONO (3700 1725);
DISPLAY INVISIBLE (3700 1725);
FORCEPROP 2 LAST CDS_SEC 1
J 0
(3700 1725);
DISPLAY 1.021277 (3700 1725);
DISPLAY INVISIBLE (3700 1725);
FORCEPROP 1 LASTPIN (3650 1600) $PN 1
J 0
(3655 1562);
DISPLAY 0.787234 (3655 1562);
FORCEPROP 1 LASTPIN (3650 1400) $PN 2
J 0
(3655 1410);
DISPLAY 0.787234 (3655 1410);
FORCEPROP 1 LAST MATERIAL CHIP
J 0
(3690 1425);
DISPLAY 0.638298 (3690 1425);
FORCEPROP 1 LAST WATTAGE 1/16W
J 0
(3690 1475);
DISPLAY 0.638298 (3690 1475);
FORCEPROP 1 LAST PACK_TYPE 0402LF
J 0
(3690 1375);
DISPLAY 0.638298 (3690 1375);
FORCEPROP 1 LAST TOLERANCE 5%
J 0
(3695 1525);
DISPLAY 0.638298 (3695 1525);
FORCEPROP 1 LAST VALUE 4.7K
J 0
(3695 1575);
DISPLAY 0.638298 (3695 1575);
FORCEPROP 2 LAST CDS_LIB pure_quanta
J 0
(3650 1500);
PAINT MONO (3650 1500);
DISPLAY INVISIBLE (3650 1500);
FORCEPROP 1 LAST PATH I88
J 0
(3700 1675);
DISPLAY 0.978723 (3700 1675);
PAINT WHITE (3700 1675);
DISPLAY INVISIBLE (3700 1675);
FORCEPROP 1 LAST PART_NUMBER CS24702JB10
J 0
(3690 1325);
DISPLAY 0.638298 (3690 1325);
DISPLAY INVISIBLE (3690 1325);
FORCEADD UNIVERSAL_POWER..1
(3650 1725);
FORCEPROP 3 LASTPIN (3650 1675) SIG_NAME P3V3_AUX\g
J 0
(3660 1685);
DISPLAY 0.659574 (3660 1685);
PAINT MONO (3660 1685);
DISPLAY INVISIBLE (3660 1685);
FORCEPROP 1 LAST HDL_POWER P3V3_AUX
J 1
(3650 1775);
DISPLAY 0.872340 (3650 1775);
PAINT GREEN (3650 1775);
FORCEPROP 2 LAST CDS_LIB pure_quanta_power
J 0
(3650 1725);
PAINT MONO (3650 1725);
DISPLAY INVISIBLE (3650 1725);
FORCEPROP 1 LAST PATH I89
J 0
(3700 1750);
DISPLAY 0.872340 (3700 1750);
PAINT AQUA (3700 1750);
DISPLAY INVISIBLE (3700 1750);
FORCEADD UNIVERSAL_POWER..1
(-900 -125);
FORCEPROP 3 LASTPIN (-900 -175) SIG_NAME P3V3_AUX\g
J 0
(-890 -165);
DISPLAY 0.659574 (-890 -165);
PAINT MONO (-890 -165);
DISPLAY INVISIBLE (-890 -165);
FORCEPROP 1 LAST HDL_POWER P3V3_AUX
J 1
(-900 -75);
DISPLAY 0.872340 (-900 -75);
PAINT GREEN (-900 -75);
FORCEPROP 2 LAST CDS_LIB pure_quanta_power
J 0
(-900 -125);
PAINT MONO (-900 -125);
DISPLAY INVISIBLE (-900 -125);
FORCEPROP 1 LAST PATH I9
J 0
(-850 -100);
DISPLAY 0.872340 (-850 -100);
PAINT AQUA (-850 -100);
DISPLAY INVISIBLE (-850 -100);
FORCEADD UNIVERSAL_GND..1
(3675 1975);
FORCEPROP 3 LASTPIN (3675 2025) SIG_NAME GND\g
J 0
(3685 2035);
DISPLAY 0.659574 (3685 2035);
PAINT MONO (3685 2035);
DISPLAY INVISIBLE (3685 2035);
FORCEPROP 2 LAST CDS_LIB pure_quanta_power
J 0
(3675 1975);
DISPLAY INVISIBLE (3675 1975);
FORCEPROP 1 LAST HDL_POWER GND
J 1
(3700 1900);
DISPLAY 0.872340 (3700 1900);
PAINT GREEN (3700 1900);
DISPLAY INVISIBLE (3700 1900);
FORCEPROP 1 LAST PATH I90
J 0
(3750 1975);
DISPLAY 0.872340 (3750 1975);
PAINT AQUA (3750 1975);
DISPLAY INVISIBLE (3750 1975);
FORCEADD Q_RES..1
(3925 1875);
FORCEPROP 1 LAST LOCATION R4576
J 0
(3700 1875);
DISPLAY 0.787234 (3700 1875);
FORCEPROP 0 LAST $SEC 1
J 0
(4175 2000);
DISPLAY 0.680851 (4175 2000);
PAINT MONO (4175 2000);
DISPLAY INVISIBLE (4175 2000);
FORCEPROP 0 LAST CDS_SEC 1
J 0
(4175 2000);
DISPLAY 1.021277 (4175 2000);
DISPLAY INVISIBLE (4175 2000);
FORCEPROP 1 LASTPIN (3825 1875) $PN 1
J 0
(3837 1887);
DISPLAY 0.787234 (3837 1887);
PAINT MONO (3837 1887);
FORCEPROP 1 LASTPIN (4025 1875) $PN 2
J 0
(3987 1887);
DISPLAY 0.787234 (3987 1887);
PAINT MONO (3987 1887);
FORCEPROP 1 LAST PACK_TYPE 0402LF
J 0
(3825 1975);
DISPLAY 0.510638 (3825 1975);
FORCEPROP 1 LAST TOLERANCE 5%
J 0
(4075 1875);
DISPLAY 0.510638 (4075 1875);
FORCEPROP 1 LAST MATERIAL EMPTY
J 0
(4150 1875);
DISPLAY 0.510638 (4150 1875);
PAINT RED (4150 1875);
FORCEPROP 1 LAST VALUE 0
J 2
(4050 1875);
DISPLAY 0.510638 (4050 1875);
FORCEPROP 1 LAST WATTAGE 1/16W
J 2
(4175 1975);
DISPLAY 0.510638 (4175 1975);
FORCEPROP 2 LAST CDS_LIB pure_quanta
J 0
(3925 1875);
DISPLAY INVISIBLE (3925 1875);
FORCEPROP 1 LAST PATH I91
J 0
(3875 2025);
DISPLAY 0.978723 (3875 2025);
PAINT WHITE (3875 2025);
DISPLAY INVISIBLE (3875 2025);
FORCEPROP 1 LAST PART_NUMBER CS00002JB13
J 0
(3875 1925);
DISPLAY 0.510638 (3875 1925);
DISPLAY INVISIBLE (3875 1925);
FORCEADD Q_RES..2
(2525 2100);
FORCEPROP 1 LAST LOCATION R4136
J 0
(2570 2225);
DISPLAY 0.978723 (2570 2225);
FORCEPROP 0 LAST $SEC 1
J 0
(2575 2275);
DISPLAY 0.680851 (2575 2275);
PAINT MONO (2575 2275);
DISPLAY INVISIBLE (2575 2275);
FORCEPROP 0 LAST CDS_SEC 1
J 0
(2575 2275);
DISPLAY 1.021277 (2575 2275);
DISPLAY INVISIBLE (2575 2275);
FORCEPROP 1 LASTPIN (2525 2200) $PN 1
J 0
(2530 2162);
DISPLAY 0.787234 (2530 2162);
PAINT MONO (2530 2162);
FORCEPROP 1 LASTPIN (2525 2000) $PN 2
J 0
(2530 2010);
DISPLAY 0.787234 (2530 2010);
PAINT MONO (2530 2010);
FORCEPROP 1 LAST WATTAGE 1/16W
J 0
(2565 2075);
DISPLAY 0.510638 (2565 2075);
FORCEPROP 1 LAST TOLERANCE 1%
J 0
(2570 2125);
DISPLAY 0.510638 (2570 2125);
FORCEPROP 1 LAST PACK_TYPE 0402LF
J 0
(2565 1925);
DISPLAY 0.510638 (2565 1925);
FORCEPROP 1 LAST MATERIAL EMPTY
J 0
(2565 2025);
DISPLAY 0.510638 (2565 2025);
PAINT RED (2565 2025);
FORCEPROP 1 LAST VALUE 100K
J 0
(2570 2175);
DISPLAY 0.510638 (2570 2175);
FORCEPROP 2 LAST CDS_LIB pure_quanta
J 0
(2525 2100);
DISPLAY INVISIBLE (2525 2100);
FORCEPROP 1 LAST PATH I92
J 0
(2575 2275);
DISPLAY 0.978723 (2575 2275);
PAINT WHITE (2575 2275);
DISPLAY INVISIBLE (2575 2275);
FORCEPROP 1 LAST PART_NUMBER CS41002FB09
J 0
(2565 1975);
DISPLAY 0.510638 (2565 1975);
DISPLAY INVISIBLE (2565 1975);
FORCEADD Q_RES..2
(2500 2575);
FORCEPROP 1 LAST LOCATION R4135
J 0
(2545 2700);
DISPLAY 0.978723 (2545 2700);
FORCEPROP 0 LAST $SEC 1
J 0
(2550 2750);
DISPLAY 0.680851 (2550 2750);
PAINT MONO (2550 2750);
DISPLAY INVISIBLE (2550 2750);
FORCEPROP 0 LAST CDS_SEC 1
J 0
(2550 2750);
DISPLAY 0.680851 (2550 2750);
DISPLAY INVISIBLE (2550 2750);
FORCEPROP 1 LASTPIN (2500 2675) $PN 1
J 0
(2505 2637);
DISPLAY 0.787234 (2505 2637);
PAINT MONO (2505 2637);
FORCEPROP 1 LASTPIN (2500 2475) $PN 2
J 0
(2505 2485);
DISPLAY 0.787234 (2505 2485);
PAINT MONO (2505 2485);
FORCEPROP 1 LAST PACK_TYPE 0402LF
J 0
(2540 2400);
DISPLAY 0.978723 (2540 2400);
FORCEPROP 1 LAST WATTAGE 1/16W
J 0
(2540 2550);
DISPLAY 0.978723 (2540 2550);
FORCEPROP 1 LAST MATERIAL CHIP
J 0
(2540 2500);
DISPLAY 0.978723 (2540 2500);
FORCEPROP 1 LAST TOLERANCE 1%
J 0
(2545 2600);
DISPLAY 0.978723 (2545 2600);
FORCEPROP 1 LAST VALUE 10K
J 0
(2545 2650);
DISPLAY 0.978723 (2545 2650);
FORCEPROP 2 LAST CDS_LIB pure_quanta
J 0
(2500 2575);
DISPLAY INVISIBLE (2500 2575);
FORCEPROP 1 LAST PATH I93
J 0
(2550 2750);
DISPLAY 0.978723 (2550 2750);
PAINT WHITE (2550 2750);
DISPLAY INVISIBLE (2550 2750);
FORCEPROP 1 LAST PART_NUMBER CS31002FB08
J 0
(2540 2450);
DISPLAY 0.978723 (2540 2450);
DISPLAY INVISIBLE (2540 2450);
FORCEADD UNIVERSAL_POWER..1
(2500 2825);
FORCEPROP 3 LASTPIN (2500 2775) SIG_NAME P3V3_AUX\g
J 0
(2510 2785);
DISPLAY 0.659574 (2510 2785);
PAINT MONO (2510 2785);
DISPLAY INVISIBLE (2510 2785);
FORCEPROP 1 LAST HDL_POWER P3V3_AUX
J 1
(2500 2875);
DISPLAY 0.872340 (2500 2875);
PAINT GREEN (2500 2875);
FORCEPROP 2 LAST CDS_LIB pure_quanta_power
J 0
(2500 2825);
PAINT MONO (2500 2825);
DISPLAY INVISIBLE (2500 2825);
FORCEPROP 1 LAST PATH I94
J 0
(2550 2850);
DISPLAY 0.872340 (2550 2850);
PAINT AQUA (2550 2850);
DISPLAY INVISIBLE (2550 2850);
FORCEADD UNIVERSAL_GND..1
(2500 3200);
FORCEPROP 3 LASTPIN (2500 3250) SIG_NAME GND\g
J 0
(2510 3260);
DISPLAY 0.659574 (2510 3260);
PAINT MONO (2510 3260);
DISPLAY INVISIBLE (2510 3260);
FORCEPROP 2 LAST CDS_LIB pure_quanta_power
J 0
(2500 3200);
DISPLAY INVISIBLE (2500 3200);
FORCEPROP 1 LAST HDL_POWER GND
J 1
(2525 3125);
DISPLAY 0.872340 (2525 3125);
PAINT GREEN (2525 3125);
DISPLAY INVISIBLE (2525 3125);
FORCEPROP 1 LAST PATH I95
J 0
(2575 3200);
DISPLAY 0.872340 (2575 3200);
PAINT AQUA (2575 3200);
DISPLAY INVISIBLE (2575 3200);
FORCEADD Q_RES..2
(2500 3475);
FORCEPROP 1 LAST LOCATION R4132
J 0
(2545 3600);
DISPLAY 0.978723 (2545 3600);
FORCEPROP 0 LAST $SEC 1
J 0
(2550 3650);
DISPLAY 0.680851 (2550 3650);
PAINT MONO (2550 3650);
DISPLAY INVISIBLE (2550 3650);
FORCEPROP 0 LAST CDS_SEC 1
J 0
(2550 3650);
DISPLAY 1.021277 (2550 3650);
DISPLAY INVISIBLE (2550 3650);
FORCEPROP 1 LASTPIN (2500 3575) $PN 1
J 0
(2505 3537);
DISPLAY 0.787234 (2505 3537);
PAINT MONO (2505 3537);
FORCEPROP 1 LASTPIN (2500 3375) $PN 2
J 0
(2505 3385);
DISPLAY 0.787234 (2505 3385);
PAINT MONO (2505 3385);
FORCEPROP 1 LAST WATTAGE 1/16W
J 0
(2540 3450);
DISPLAY 0.510638 (2540 3450);
FORCEPROP 1 LAST TOLERANCE 1%
J 0
(2545 3500);
DISPLAY 0.510638 (2545 3500);
FORCEPROP 1 LAST VALUE 100K
J 0
(2545 3550);
DISPLAY 0.510638 (2545 3550);
FORCEPROP 1 LAST MATERIAL EMPTY
J 0
(2540 3400);
DISPLAY 0.510638 (2540 3400);
PAINT RED (2540 3400);
FORCEPROP 1 LAST PACK_TYPE 0402LF
J 0
(2540 3300);
DISPLAY 0.510638 (2540 3300);
FORCEPROP 2 LAST CDS_LIB pure_quanta
J 0
(2500 3475);
DISPLAY INVISIBLE (2500 3475);
FORCEPROP 1 LAST PATH I96
J 0
(2550 3650);
DISPLAY 0.978723 (2550 3650);
PAINT WHITE (2550 3650);
DISPLAY INVISIBLE (2550 3650);
FORCEPROP 1 LAST PART_NUMBER CS41002FB09
J 0
(2540 3350);
DISPLAY 0.510638 (2540 3350);
DISPLAY INVISIBLE (2540 3350);
FORCEADD Q_RES..2
(2475 3950);
FORCEPROP 1 LAST LOCATION R4131
J 0
(2520 4075);
DISPLAY 0.978723 (2520 4075);
FORCEPROP 0 LAST $SEC 1
J 0
(2525 4125);
DISPLAY 0.680851 (2525 4125);
PAINT MONO (2525 4125);
DISPLAY INVISIBLE (2525 4125);
FORCEPROP 0 LAST CDS_SEC 1
J 0
(2525 4125);
DISPLAY 1.021277 (2525 4125);
DISPLAY INVISIBLE (2525 4125);
FORCEPROP 1 LASTPIN (2475 4050) $PN 1
J 0
(2480 4012);
DISPLAY 0.787234 (2480 4012);
PAINT MONO (2480 4012);
FORCEPROP 1 LASTPIN (2475 3850) $PN 2
J 0
(2480 3860);
DISPLAY 0.787234 (2480 3860);
PAINT MONO (2480 3860);
FORCEPROP 1 LAST TOLERANCE 1%
J 0
(2520 3975);
DISPLAY 0.787234 (2520 3975);
FORCEPROP 1 LAST VALUE 54.9K
J 0
(2520 4025);
DISPLAY 0.787234 (2520 4025);
FORCEPROP 1 LAST PACK_TYPE 0402LF
J 0
(2515 3775);
DISPLAY 0.787234 (2515 3775);
FORCEPROP 1 LAST MATERIAL EMPTY
J 0
(2515 3875);
DISPLAY 0.787234 (2515 3875);
PAINT RED (2515 3875);
FORCEPROP 1 LAST WATTAGE 1/16W
J 0
(2515 3925);
DISPLAY 0.787234 (2515 3925);
FORCEPROP 2 LAST CDS_LIB pure_quanta
J 0
(2475 3950);
DISPLAY INVISIBLE (2475 3950);
FORCEPROP 1 LAST PATH I97
J 0
(2525 4125);
DISPLAY 0.978723 (2525 4125);
PAINT WHITE (2525 4125);
DISPLAY INVISIBLE (2525 4125);
FORCEPROP 1 LAST PART_NUMBER CS35492FB03
J 0
(2515 3825);
DISPLAY 0.787234 (2515 3825);
DISPLAY INVISIBLE (2515 3825);
FORCEADD MOSFET_NCH_DUAL..1
(3625 2350);
FORCEPROP 1 LAST LOCATION Q133
J 0
(3776 2324);
DISPLAY 0.723404 (3776 2324);
PAINT GREEN (3776 2324);
FORCEPROP 0 LAST $SEC 1
J 0
(3800 2475);
DISPLAY 0.680851 (3800 2475);
PAINT MONO (3800 2475);
DISPLAY INVISIBLE (3800 2475);
FORCEPROP 2 LAST CDS_SEC 1
J 0
(3800 2475);
DISPLAY 1.021277 (3800 2475);
DISPLAY INVISIBLE (3800 2475);
FORCEPROP 0 LASTPIN (3675 2550) $PN 6
R 1
J 0
(3665 2560);
DISPLAY 0.680851 (3665 2560);
PAINT MONO (3665 2560);
FORCEPROP 0 LASTPIN (3425 2300) $PN 2
J 2
(3415 2310);
DISPLAY 0.680851 (3415 2310);
PAINT MONO (3415 2310);
FORCEPROP 0 LASTPIN (3675 2150) $PN 1
R 1
J 2
(3665 2140);
DISPLAY 0.680851 (3665 2140);
PAINT MONO (3665 2140);
FORCEPROP 1 LAST MATERIAL IC
J 0
(3776 2199);
DISPLAY 0.723404 (3776 2199);
PAINT GREEN (3776 2199);
FORCEPROP 2 LAST PART_TYPE SMLF
J 0
(3800 2425);
DISPLAY 1.021277 (3800 2425);
FORCEPROP 2 LAST VALUE PJT138K
J 0
(3800 2375);
DISPLAY 1.021277 (3800 2375);
FORCEPROP 1 LAST CDS_LMAN_SYM_OUTLINE -150,150,150,-150
J 0
(3625 2350);
DISPLAY 0.468085 (3625 2350);
PAINT GREEN (3625 2350);
DISPLAY INVISIBLE (3625 2350);
FORCEPROP 1 LAST NEEDS_NO_SIZE TRUE
J 0
(3625 2349);
DISPLAY 0.468085 (3625 2349);
PAINT GREEN (3625 2349);
DISPLAY INVISIBLE (3625 2349);
FORCEPROP 2 LAST CDS_LIB pure_quanta
J 0
(3625 2350);
DISPLAY INVISIBLE (3625 2350);
FORCEPROP 1 LAST PATH I98
J 0
(3625 2350);
DISPLAY 0.723404 (3625 2350);
PAINT GREEN (3625 2350);
DISPLAY INVISIBLE (3625 2350);
FORCEPROP 1 LAST PART_NUMBER BAM138K0003
J 0
(3776 2264);
DISPLAY 0.723404 (3776 2264);
PAINT GREEN (3776 2264);
DISPLAY INVISIBLE (3776 2264);
FORCEADD Q_RES..2
(3675 2950);
FORCEPROP 1 LAST LOCATION R4139
J 0
(3720 3075);
DISPLAY 0.638298 (3720 3075);
FORCEPROP 2 LAST $SEC 1
J 0
(3725 3175);
DISPLAY 0.680851 (3725 3175);
PAINT MONO (3725 3175);
DISPLAY INVISIBLE (3725 3175);
FORCEPROP 2 LAST CDS_SEC 1
J 0
(3725 3175);
DISPLAY 1.021277 (3725 3175);
DISPLAY INVISIBLE (3725 3175);
FORCEPROP 1 LASTPIN (3675 3050) $PN 1
J 0
(3680 3012);
DISPLAY 0.787234 (3680 3012);
FORCEPROP 1 LASTPIN (3675 2850) $PN 2
J 0
(3680 2860);
DISPLAY 0.787234 (3680 2860);
FORCEPROP 1 LAST TOLERANCE 5%
J 0
(3720 2975);
DISPLAY 0.638298 (3720 2975);
FORCEPROP 1 LAST VALUE 4.7K
J 0
(3720 3025);
DISPLAY 0.638298 (3720 3025);
FORCEPROP 1 LAST WATTAGE 1/16W
J 0
(3715 2925);
DISPLAY 0.638298 (3715 2925);
FORCEPROP 1 LAST MATERIAL CHIP
J 0
(3715 2875);
DISPLAY 0.638298 (3715 2875);
FORCEPROP 1 LAST PACK_TYPE 0402LF
J 0
(3715 2825);
DISPLAY 0.638298 (3715 2825);
FORCEPROP 2 LAST CDS_LIB pure_quanta
J 0
(3675 2950);
PAINT MONO (3675 2950);
DISPLAY INVISIBLE (3675 2950);
FORCEPROP 1 LAST PATH I99
J 0
(3725 3125);
DISPLAY 0.978723 (3725 3125);
PAINT WHITE (3725 3125);
DISPLAY INVISIBLE (3725 3125);
FORCEPROP 1 LAST PART_NUMBER CS24702JB10
J 0
(3715 2775);
DISPLAY 0.638298 (3715 2775);
DISPLAY INVISIBLE (3715 2775);
FORCEADD DNS..2
(2500 3450);
PAINT RED (2500 3450);
FORCEPROP 2 LAST CDS_LIB mstr_misc
J 0
(2500 3450);
DISPLAY INVISIBLE (2500 3450);
FORCEPROP 1 LAST COMMENT_BODY TRUE
J 0
(2500 3450);
DISPLAY INVISIBLE (2500 3450);
FORCEADD DNS..2
(2525 2075);
PAINT RED (2525 2075);
FORCEPROP 2 LAST CDS_LIB mstr_misc
J 0
(2525 2075);
DISPLAY INVISIBLE (2525 2075);
FORCEPROP 1 LAST COMMENT_BODY TRUE
J 0
(2525 2075);
DISPLAY INVISIBLE (2525 2075);
FORCEADD DNS..2
(3975 4700);
PAINT RED (3975 4700);
FORCEPROP 2 LAST CDS_LIB mstr_misc
J 0
(3975 4700);
DISPLAY INVISIBLE (3975 4700);
FORCEPROP 1 LAST COMMENT_BODY TRUE
J 0
(3975 4700);
DISPLAY INVISIBLE (3975 4700);
FORCEADD DNS..2
(2475 3925);
PAINT RED (2475 3925);
FORCEPROP 2 LAST CDS_LIB mstr_misc
J 0
(2475 3925);
DISPLAY INVISIBLE (2475 3925);
FORCEPROP 1 LAST COMMENT_BODY TRUE
J 0
(2475 3925);
DISPLAY INVISIBLE (2475 3925);
FORCEADD DNS..2
(3950 1875);
PAINT RED (3950 1875);
FORCEPROP 2 LAST CDS_LIB mstr_misc
J 0
(3950 1875);
DISPLAY INVISIBLE (3950 1875);
FORCEPROP 1 LAST COMMENT_BODY TRUE
J 0
(3950 1875);
DISPLAY INVISIBLE (3950 1875);
FORCEADD DNS..2
(4025 3325);
PAINT RED (4025 3325);
FORCEPROP 2 LAST CDS_LIB mstr_misc
J 0
(4025 3325);
DISPLAY INVISIBLE (4025 3325);
FORCEPROP 1 LAST COMMENT_BODY TRUE
J 0
(4025 3325);
DISPLAY INVISIBLE (4025 3325);
FORCEADD DNS..2
(-675 3025);
PAINT RED (-675 3025);
FORCEPROP 2 LAST CDS_LIB mstr_misc
J 0
(-675 3025);
DISPLAY INVISIBLE (-675 3025);
FORCEPROP 1 LAST COMMENT_BODY TRUE
J 0
(-675 3025);
DISPLAY INVISIBLE (-675 3025);
FORCEADD DNS..2
(-2150 3625);
PAINT RED (-2150 3625);
FORCEPROP 2 LAST CDS_LIB mstr_misc
J 0
(-2150 3625);
DISPLAY INVISIBLE (-2150 3625);
FORCEPROP 1 LAST COMMENT_BODY TRUE
J 0
(-2150 3625);
DISPLAY INVISIBLE (-2150 3625);
FORCEADD DNS..2
(-2125 3150);
PAINT RED (-2125 3150);
FORCEPROP 2 LAST CDS_LIB mstr_misc
J 0
(-2125 3150);
DISPLAY INVISIBLE (-2125 3150);
FORCEPROP 1 LAST COMMENT_BODY TRUE
J 0
(-2125 3150);
DISPLAY INVISIBLE (-2125 3150);
FORCEADD DNS..2
(-2125 2250);
PAINT RED (-2125 2250);
FORCEPROP 2 LAST CDS_LIB mstr_misc
J 0
(-2125 2250);
DISPLAY INVISIBLE (-2125 2250);
FORCEPROP 1 LAST COMMENT_BODY TRUE
J 0
(-2125 2250);
DISPLAY INVISIBLE (-2125 2250);
FORCEADD DNS..2
(-675 1575);
PAINT RED (-675 1575);
FORCEPROP 2 LAST CDS_LIB mstr_misc
J 0
(-675 1575);
DISPLAY INVISIBLE (-675 1575);
FORCEPROP 1 LAST COMMENT_BODY TRUE
J 0
(-675 1575);
DISPLAY INVISIBLE (-675 1575);
FORCEADD DNS..2
(-2100 1775);
PAINT RED (-2100 1775);
FORCEPROP 2 LAST CDS_LIB mstr_misc
J 0
(-2100 1775);
DISPLAY INVISIBLE (-2100 1775);
FORCEPROP 1 LAST COMMENT_BODY TRUE
J 0
(-2100 1775);
DISPLAY INVISIBLE (-2100 1775);
FORCEADD DNS..2
(-2125 325);
PAINT RED (-2125 325);
FORCEPROP 2 LAST CDS_LIB mstr_misc
J 0
(-2125 325);
DISPLAY INVISIBLE (-2125 325);
FORCEPROP 1 LAST COMMENT_BODY TRUE
J 0
(-2125 325);
DISPLAY INVISIBLE (-2125 325);
FORCEADD DNS..2
(-600 25);
PAINT RED (-600 25);
FORCEPROP 2 LAST CDS_LIB mstr_misc
J 0
(-600 25);
DISPLAY INVISIBLE (-600 25);
FORCEPROP 1 LAST COMMENT_BODY TRUE
J 0
(-600 25);
DISPLAY INVISIBLE (-600 25);
FORCEADD DNS..2
(-2050 -1225);
PAINT RED (-2050 -1225);
FORCEPROP 2 LAST CDS_LIB mstr_misc
J 0
(-2050 -1225);
DISPLAY INVISIBLE (-2050 -1225);
FORCEPROP 1 LAST COMMENT_BODY TRUE
J 0
(-2050 -1225);
DISPLAY INVISIBLE (-2050 -1225);
FORCEADD DNS..2
(-550 4475);
PAINT RED (-550 4475);
FORCEPROP 2 LAST CDS_LIB mstr_misc
J 0
(-550 4475);
DISPLAY INVISIBLE (-550 4475);
FORCEPROP 1 LAST COMMENT_BODY TRUE
J 0
(-550 4475);
DISPLAY INVISIBLE (-550 4475);
FORCEADD QUANTA_TITLE_BLOCK_C..1
(6500 -1700);
FORCEPROP 0 LAST CDS_CON_LAST_MODIFIED Thu Sep 14 16:13:07 2023
J 0
(4615 -1685);
PAINT MONO (4615 -1685);
DISPLAY INVISIBLE (4615 -1685);
FORCEPROP 1 LAST CUSTOM_TXT_CDS <CON_LAST_MODIFIED>
J 0
(4615 -1685);
DISPLAY 0.978723 (4615 -1685);
FORCEPROP 2 LAST CUSTOM_TXT_CDS <XR_PAGE_TITLE>
J 0
(-1390 3550);
DISPLAY 0.638298 (-1390 3550);
PAINT PINK (-1390 3550);
DISPLAY INVISIBLE (-1390 3550);
FORCEPROP 2 LAST CUSTOM_TXT_CDS <NAME_1>
J 0
(3325 -1525);
FORCEPROP 2 LAST CUSTOM_TXT_CDS <Q_REV>
J 0
(6316 -1597);
DISPLAY 1.212766 (6316 -1597);
FORCEPROP 2 LAST CUSTOM_TXT_CDS <CON_PAGE_NUM> OF <CON_TOTAL_PAGES>
J 0
(6054 -1682);
DISPLAY 0.978723 (6054 -1682);
FORCEPROP 2 LAST CUSTOM_TXT_CDS <Q_NUMBER>
J 0
(5097 -1597);
DISPLAY 1.212766 (5097 -1597);
FORCEPROP 2 LAST CUSTOM_TXT_CDS <NAME_2>
J 0
(3325 -1650);
FORCEPROP 2 LAST CUSTOM_TXT_CDS <Q_PROJ>
J 0
(4118 -1598);
DISPLAY 1.212766 (4118 -1598);
FORCEPROP 1 LAST Q_TITLE EXAMAX_ISO (2/7)
J 0
(-2750 -1625);
DISPLAY 1.957447 (-2750 -1625);
PAINT GREEN (-2750 -1625);
FORCEPROP 2 LAST PAGE_BORDER TRUE
J 0
(-1390 3550);
DISPLAY 0.638298 (-1390 3550);
PAINT PINK (-1390 3550);
DISPLAY INVISIBLE (-1390 3550);
FORCEPROP 1 LAST CDS_LMAN_SYM_OUTLINE -9475,6775,100,-125
J 0
(6500 -1700);
DISPLAY 0.468085 (6500 -1700);
PAINT GREEN (6500 -1700);
DISPLAY INVISIBLE (6500 -1700);
FORCEPROP 2 LAST CDS_LIB pure_quanta
J 0
(6500 -1700);
PAINT MONO (6500 -1700);
DISPLAY INVISIBLE (6500 -1700);
FORCEPROP 2 LAST CDS_XR_PAGE_TITLE CR-125 : @T6G_MB_LIB.T6G(SCH_1):PAGE125
J 0
(-1390 3550);
DISPLAY 0.638298 (-1390 3550);
PAINT PINK (-1390 3550);
DISPLAY INVISIBLE (-1390 3550);
FORCEPROP 1 LAST Q_DEPT BU9
J 1
(2737 -1651);
DISPLAY 1.957447 (2737 -1651);
PAINT GREEN (2737 -1651);
DISPLAY INVISIBLE (2737 -1651);
FORCEPROP 1 LAST COMMENT_BODY TRUE
J 0
(6512 -1713);
DISPLAY 0.978723 (6512 -1713);
PAINT GREEN (6512 -1713);
DISPLAY INVISIBLE (6512 -1713);
FORCEADD DNS..2
(2475 -375);
PAINT RED (2475 -375);
FORCEPROP 2 LAST CDS_LIB mstr_misc
J 0
(2475 -375);
DISPLAY INVISIBLE (2475 -375);
FORCEPROP 1 LAST COMMENT_BODY TRUE
J 0
(2475 -375);
DISPLAY INVISIBLE (2475 -375);
FORCEADD DNS..2
(2500 625);
PAINT RED (2500 625);
FORCEPROP 2 LAST CDS_LIB mstr_misc
J 0
(2500 625);
DISPLAY INVISIBLE (2500 625);
FORCEPROP 1 LAST COMMENT_BODY TRUE
J 0
(2500 625);
DISPLAY INVISIBLE (2500 625);
FORCEADD DNS..2
(2475 1100);
PAINT RED (2475 1100);
FORCEPROP 2 LAST CDS_LIB mstr_misc
J 0
(2475 1100);
DISPLAY INVISIBLE (2475 1100);
FORCEPROP 1 LAST COMMENT_BODY TRUE
J 0
(2475 1100);
DISPLAY INVISIBLE (2475 1100);
WIRE 16 -1 (-2050 -1300)(-2050 -1425);
WIRE 16 -1 (3675 3125)(3675 3050);
WIRE 16 -1 (3650 3525)(3650 3400);
WIRE 16 -1 (175 4325)(175 4250);
WIRE 16 -1 (2475 4150)(2475 4050);
WIRE 16 -1 (3650 4500)(3650 4425);
WIRE 16 -1 (4800 325)(4800 250);
WIRE 16 -1 (4800 1000)(4800 875);
WIRE 16 -1 (4800 1800)(4800 1725);
WIRE 16 -1 (5575 1050)(5575 1000);
WIRE 16 -1 (-2125 250)(-2125 125);
WIRE 16 -1 (4825 2450)(4825 2325);
WIRE 16 -1 (4825 3250)(4825 3175);
WIRE 16 -1 (4800 3825)(4800 3700);
WIRE 16 -1 (5600 2500)(5600 2450);
WIRE 16 -1 (5575 3875)(5575 3825);
WIRE 16 -1 (4800 4625)(4800 4550);
WIRE 16 -1 (-2150 1025)(-2150 925);
WIRE 16 -1 (-2100 1700)(-2100 1575);
WIRE 16 -1 (-2125 2475)(-2125 2375);
WIRE 16 -1 (-2125 3075)(-2125 2950);
WIRE 16 -1 (-2150 3850)(-2150 3750);
WIRE 16 -1 (-975 400)(-975 275);
WIRE 16 -1 (-975 1375)(-975 1300);
WIRE 16 -1 (-950 1850)(-950 1725);
WIRE 16 -1 (0 1425)(175 1425);
WIRE 16 -1 (-950 2825)(-950 2750);
WIRE 16 -1 (-975 3225)(-975 3100);
WIRE 16 -1 (-975 4200)(-975 4125);
WIRE 16 -1 (175 3525)(175 3400);
WIRE 16 -1 (175 700)(175 575);
WIRE 16 -1 (250 -850)(250 -975);
WIRE 16 -1 (1025 -800)(1025 -850);
WIRE 16 -1 (-2075 -525)(-2075 -625);
WIRE 16 -1 (2500 -925)(2500 -1050);
WIRE 16 -1 (2475 -150)(2475 -250);
WIRE 16 -1 (3650 -775)(3650 -900);
WIRE 16 -1 (4800 -475)(4800 -600);
WIRE 16 -1 (5575 -425)(5575 -475);
WIRE 16 -1 (250 -50)(250 -125);
WIRE 16 -1 (950 750)(950 700);
WIRE 16 -1 (200 2150)(200 2025);
WIRE 16 -1 (-900 -1150)(-900 -1275);
WIRE 16 -1 (200 2950)(200 2875);
WIRE 16 -1 (975 2200)(975 2150);
WIRE 16 -1 (950 3575)(950 3525);
WIRE 16 -1 (2500 550)(2500 425);
WIRE 16 -1 (2475 1325)(2475 1225);
WIRE 16 -1 (2525 2000)(2525 1875);
WIRE 16 -1 (3650 200)(3650 125);
WIRE 16 -1 (3650 700)(3650 575);
WIRE 16 -1 (3650 1675)(3650 1600);
WIRE 16 -1 (-900 -175)(-900 -250);
WIRE 16 -1 (3675 2150)(3675 2025);
WIRE 16 -1 (2500 2775)(2500 2675);
WIRE 16 -1 (2500 3375)(2500 3250);
WIRE 16 -1 (4800 50)(4800 -25);
WIRE 16 -1 (5575 -25)(4800 -25);
FORCEPROP 2 LAST SIG_NAME SWB_HSC_PWRGD_ISO
J 0
(5015 -15);
DISPLAY 0.808511 (5015 -15);
WIRE 16 -1 (4800 -25)(4800 -75);
WIRE 16 -1 (5875 -25)(5575 -25);
WIRE 16 -1 (5575 -225)(5575 -25);
WIRE 16 -1 (2500 -725)(2500 -625);
WIRE 16 -1 (3400 -625)(2500 -625);
FORCEPROP 2 LAST SIG_NAME SWB_HSC_PWRGD
J 0
(2515 -615);
DISPLAY 0.808511 (2515 -615);
WIRE 16 -1 (2500 -625)(2475 -625);
WIRE 16 -1 (2475 -450)(2475 -625);
WIRE 16 -1 (2475 -625)(2275 -625);
WIRE 16 -1 (250 -325)(250 -400);
WIRE 16 -1 (1025 -400)(250 -400);
FORCEPROP 2 LAST SIG_NAME PRSNT_CABLE_GPU_A1_ISO_N
J 0
(315 -390);
DISPLAY 0.808511 (315 -390);
WIRE 16 -1 (250 -400)(250 -450);
WIRE 16 -1 (1075 -400)(1025 -400);
WIRE 16 -1 (1025 -600)(1025 -400);
WIRE 16 -1 (1075 25)(1075 -400);
WIRE 16 -1 (1325 -400)(1075 -400);
WIRE 16 -1 (-525 25)(1075 25);
WIRE 16 -1 (-600 1575)(1000 1575);
WIRE 16 -1 (1000 1575)(1000 1150);
WIRE 16 -1 (1250 1150)(1000 1150);
WIRE 16 -1 (1000 1150)(950 1150);
WIRE 16 -1 (950 1150)(175 1150);
FORCEPROP 2 LAST SIG_NAME PRSNT_CABLE_GPU_B3_ISO_N
J 0
(240 1160);
DISPLAY 0.808511 (240 1160);
WIRE 16 -1 (950 950)(950 1150);
WIRE 16 -1 (175 1150)(175 1100);
WIRE 16 -1 (175 1225)(175 1150);
WIRE 16 -1 (1000 2600)(975 2600);
WIRE 16 -1 (1275 2600)(1000 2600);
WIRE 16 -1 (1000 3025)(1000 2600);
WIRE 16 -1 (975 2400)(975 2600);
WIRE 16 -1 (975 2600)(200 2600);
FORCEPROP 2 LAST SIG_NAME GPU_3V3IO_RSVD1_FFU_ISO
J 0
(265 2610);
DISPLAY 0.808511 (265 2610);
WIRE 16 -1 (200 2675)(200 2600);
WIRE 16 -1 (200 2600)(200 2550);
WIRE 16 -1 (-600 3025)(1000 3025);
WIRE 16 -1 (-900 -450)(-900 -700);
WIRE 16 -1 (0 -700)(-900 -700);
FORCEPROP 2 LAST SIG_NAME PRSNT_CABLE_GPU_A1
J 0
(-835 -690);
DISPLAY 0.808511 (-835 -690);
FORCEPROP 2 LASTPROP $XRERR UNIQUE?
J 0
(-1075 -690);
DISPLAY 0.638298 (-1075 -690);
PAINT MONO (-1075 -690);
DISPLAY INVISIBLE (-1075 -690);
WIRE 16 -1 (-900 -750)(-900 -700);
WIRE 16 -1 (3650 -75)(3650 -325);
WIRE 16 -1 (4550 -325)(3650 -325);
FORCEPROP 2 LAST SIG_NAME SWB_HSC_PWRGD_N
J 0
(3715 -315);
DISPLAY 0.808511 (3715 -315);
FORCEPROP 2 LASTPROP $XRERR UNIQUE?
J 0
(3475 -315);
DISPLAY 0.638298 (3475 -315);
PAINT MONO (3475 -315);
DISPLAY INVISIBLE (3475 -315);
WIRE 16 -1 (3650 -375)(3650 -325);
WIRE 16 -1 (-75 850)(-975 850);
FORCEPROP 2 LAST SIG_NAME PRSNT_CABLE_GPU_B3
J 0
(-910 860);
DISPLAY 0.808511 (-910 860);
FORCEPROP 2 LASTPROP $XRERR UNIQUE?
J 0
(-1150 860);
DISPLAY 0.638298 (-1150 860);
PAINT MONO (-1150 860);
DISPLAY INVISIBLE (-1150 860);
WIRE 16 -1 (-975 1100)(-975 850);
WIRE 16 -1 (-975 800)(-975 850);
WIRE 16 -1 (-975 3925)(-975 3675);
WIRE 16 -1 (-75 3675)(-975 3675);
FORCEPROP 2 LAST SIG_NAME GPU_3V3IO_RSVD0_FFU_N
J 0
(-910 3685);
DISPLAY 0.808511 (-910 3685);
FORCEPROP 2 LASTPROP $XRERR UNIQUE?
J 0
(-1150 3685);
DISPLAY 0.638298 (-1150 3685);
PAINT MONO (-1150 3685);
DISPLAY INVISIBLE (-1150 3685);
WIRE 16 -1 (-975 3625)(-975 3675);
WIRE 16 -1 (3650 1400)(3650 1150);
WIRE 16 -1 (4550 1150)(3650 1150);
FORCEPROP 2 LAST SIG_NAME GPU_3V3IO_RSVD5_FFU_N
J 0
(3715 1160);
DISPLAY 0.808511 (3715 1160);
FORCEPROP 2 LASTPROP $XRERR UNIQUE?
J 0
(3475 1160);
DISPLAY 0.638298 (3475 1160);
PAINT MONO (3475 1160);
DISPLAY INVISIBLE (3475 1160);
WIRE 16 -1 (3650 1100)(3650 1150);
WIRE 16 -1 (3675 2850)(3675 2600);
WIRE 16 -1 (4575 2600)(3675 2600);
FORCEPROP 2 LAST SIG_NAME PRSNT_CABLE_GPU_A2
J 0
(3740 2610);
DISPLAY 0.808511 (3740 2610);
FORCEPROP 2 LASTPROP $XRERR UNIQUE?
J 0
(3500 2610);
DISPLAY 0.638298 (3500 2610);
PAINT MONO (3500 2610);
DISPLAY INVISIBLE (3500 2610);
WIRE 16 -1 (3675 2550)(3675 2600);
WIRE 16 -1 (3650 4225)(3650 3975);
WIRE 16 -1 (4550 3975)(3650 3975);
FORCEPROP 2 LAST SIG_NAME GPU_3V3IO_RSVD3_FFU_N
J 0
(3715 3985);
DISPLAY 0.808511 (3715 3985);
FORCEPROP 2 LASTPROP $XRERR UNIQUE?
J 0
(3475 3985);
DISPLAY 0.638298 (3475 3985);
PAINT MONO (3475 3985);
DISPLAY INVISIBLE (3475 3985);
WIRE 16 -1 (3650 3925)(3650 3975);
WIRE 16 -1 (-950 2550)(-950 2300);
WIRE 16 -1 (-50 2300)(-950 2300);
FORCEPROP 2 LAST SIG_NAME GPU_3V3IO_RSVD1_FFU_N
J 0
(-885 2310);
DISPLAY 0.808511 (-885 2310);
FORCEPROP 2 LASTPROP $XRERR UNIQUE?
J 0
(-1125 2310);
DISPLAY 0.638298 (-1125 2310);
PAINT MONO (-1125 2310);
DISPLAY INVISIBLE (-1125 2310);
WIRE 16 -1 (-950 2250)(-950 2300);
WIRE 16 -1 (-1250 25)(-725 25);
WIRE 16 -1 (-1250 25)(-1250 -1000);
WIRE 16 -1 (-1150 -1000)(-1250 -1000);
WIRE 16 -1 (-1250 -1000)(-2050 -1000);
FORCEPROP 2 LAST SIG_NAME PRSNT_CABLE_GPU_A1_N
J 0
(-2010 -990);
DISPLAY 0.808511 (-2010 -990);
WIRE 16 -1 (-2050 -1000)(-2075 -1000);
WIRE 16 -1 (-2050 -1100)(-2050 -1000);
WIRE 16 -1 (-2075 -1000)(-2275 -1000);
WIRE 16 -1 (-2075 -825)(-2075 -1000);
WIRE 16 -1 (-1325 1575)(-800 1575);
WIRE 16 -1 (-1325 1575)(-1325 550);
WIRE 16 -1 (-1225 550)(-1325 550);
WIRE 16 -1 (-1325 550)(-2125 550);
FORCEPROP 2 LAST SIG_NAME PRSNT_CABLE_GPU_B3_N
J 0
(-2085 560);
DISPLAY 0.808511 (-2085 560);
WIRE 16 -1 (-2125 550)(-2150 550);
WIRE 16 -1 (-2125 450)(-2125 550);
WIRE 16 -1 (-2150 725)(-2150 550);
WIRE 16 -1 (-2150 550)(-2350 550);
WIRE 16 -1 (-1325 3025)(-800 3025);
WIRE 16 -1 (-1325 3025)(-1325 2000);
WIRE 16 -1 (-1200 2000)(-1325 2000);
WIRE 16 -1 (-1325 2000)(-2100 2000);
FORCEPROP 2 LAST SIG_NAME GPU_3V3IO_RSVD1_FFU
J 0
(-2060 2010);
DISPLAY 0.808511 (-2060 2010);
WIRE 16 -1 (-2100 2000)(-2125 2000);
WIRE 16 -1 (-2100 1900)(-2100 2000);
WIRE 16 -1 (-2125 2175)(-2125 2000);
WIRE 16 -1 (-2125 2000)(-2325 2000);
WIRE 16 -1 (-1325 4475)(-675 4475);
WIRE 16 -1 (-1325 3375)(-1325 4475);
WIRE 16 -1 (-1225 3375)(-1325 3375);
WIRE 16 -1 (-1325 3375)(-2125 3375);
FORCEPROP 2 LAST SIG_NAME GPU_3V3IO_RSVD0_FFU
J 0
(-2085 3385);
DISPLAY 0.808511 (-2085 3385);
WIRE 16 -1 (-2125 3375)(-2150 3375);
WIRE 16 -1 (-2125 3275)(-2125 3375);
WIRE 16 -1 (-2150 3550)(-2150 3375);
WIRE 16 -1 (-2150 3375)(-2350 3375);
WIRE 16 -1 (175 4050)(175 3975);
WIRE 16 -1 (950 3975)(175 3975);
FORCEPROP 2 LAST SIG_NAME GPU_3V3IO_RSVD0_FFU_ISO
J 0
(240 3985);
DISPLAY 0.808511 (240 3985);
WIRE 16 -1 (175 3975)(175 3925);
WIRE 16 -1 (1125 3975)(950 3975);
WIRE 16 -1 (950 3775)(950 3975);
WIRE 16 -1 (1125 4475)(1125 3975);
WIRE 16 -1 (1250 3975)(1125 3975);
WIRE 16 -1 (-475 4475)(1125 4475);
WIRE 16 -1 (3300 1875)(3825 1875);
WIRE 16 -1 (3300 1875)(3300 850);
WIRE 16 -1 (3400 850)(3300 850);
WIRE 16 -1 (3300 850)(2500 850);
FORCEPROP 2 LAST SIG_NAME GPU_3V3IO_RSVD5_FFU
J 0
(2540 860);
DISPLAY 0.808511 (2540 860);
WIRE 16 -1 (2500 850)(2475 850);
WIRE 16 -1 (2500 750)(2500 850);
WIRE 16 -1 (2475 1025)(2475 850);
WIRE 16 -1 (2475 850)(2275 850);
WIRE 16 -1 (3375 3325)(3900 3325);
WIRE 16 -1 (3375 3325)(3375 2300);
WIRE 16 -1 (3425 2300)(3375 2300);
WIRE 16 -1 (3375 2300)(2525 2300);
FORCEPROP 2 LAST SIG_NAME PRSNT_CABLE_GPU_A2_N
J 0
(2565 2310);
DISPLAY 0.808511 (2565 2310);
WIRE 16 -1 (2525 2200)(2525 2300);
WIRE 16 -1 (2525 2300)(2500 2300);
WIRE 16 -1 (2500 2475)(2500 2300);
WIRE 16 -1 (2500 2300)(2300 2300);
WIRE 16 -1 (3325 4700)(3850 4700);
WIRE 16 -1 (3325 4700)(3325 3675);
WIRE 16 -1 (3400 3675)(3325 3675);
WIRE 16 -1 (3325 3675)(2500 3675);
FORCEPROP 2 LAST SIG_NAME GPU_3V3IO_RSVD3_FFU
J 0
(2540 3685);
DISPLAY 0.808511 (2540 3685);
WIRE 16 -1 (2500 3675)(2475 3675);
WIRE 16 -1 (2500 3575)(2500 3675);
WIRE 16 -1 (2475 3850)(2475 3675);
WIRE 16 -1 (2475 3675)(2275 3675);
WIRE 16 -1 (4800 1525)(4800 1450);
WIRE 16 -1 (5575 1450)(4800 1450);
FORCEPROP 2 LAST SIG_NAME GPU_3V3IO_RSVD5_FFU_ISO
J 0
(4865 1460);
DISPLAY 0.808511 (4865 1460);
WIRE 16 -1 (4800 1450)(4800 1400);
WIRE 16 -1 (5750 1450)(5575 1450);
WIRE 16 -1 (5575 1250)(5575 1450);
WIRE 16 -1 (5750 1875)(5750 1450);
WIRE 16 -1 (5875 1450)(5750 1450);
WIRE 16 -1 (4025 1875)(5750 1875);
WIRE 16 -1 (4825 2975)(4825 2900);
WIRE 16 -1 (5600 2900)(4825 2900);
FORCEPROP 2 LAST SIG_NAME PRSNT_CABLE_GPU_A2_ISO_N
J 0
(4890 2910);
DISPLAY 0.808511 (4890 2910);
WIRE 16 -1 (4825 2900)(4825 2850);
WIRE 16 -1 (5775 2900)(5600 2900);
WIRE 16 -1 (5600 2700)(5600 2900);
WIRE 16 -1 (5775 3325)(5775 2900);
WIRE 16 -1 (5900 2900)(5775 2900);
WIRE 16 -1 (4100 3325)(5775 3325);
WIRE 16 -1 (4800 4350)(4800 4275);
WIRE 16 -1 (5575 4275)(4800 4275);
FORCEPROP 2 LAST SIG_NAME GPU_3V3IO_RSVD3_FFU_ISO
J 0
(4865 4285);
DISPLAY 0.808511 (4865 4285);
WIRE 16 -1 (4800 4275)(4800 4225);
WIRE 16 -1 (5650 4275)(5575 4275);
WIRE 16 -1 (5575 4075)(5575 4275);
WIRE 16 -1 (5650 4700)(5650 4275);
WIRE 16 -1 (5875 4275)(5650 4275);
WIRE 16 -1 (4050 4700)(5650 4700);
DOT 1 (-2050 -1000);
DOT 1 (-2075 -1000);
DOT 1 (-1250 -1000);
DOT 1 (-900 -700);
DOT 1 (250 -400);
DOT 1 (1075 -400);
DOT 1 (1025 -400);
DOT 1 (2475 -625);
DOT 1 (2500 -625);
DOT 1 (3650 -325);
DOT 1 (4800 -25);
DOT 1 (5575 -25);
DOT 1 (-2150 550);
DOT 1 (-2125 550);
DOT 1 (-2125 2000);
DOT 1 (-2100 2000);
DOT 1 (-1325 550);
DOT 1 (-975 850);
DOT 1 (-1325 2000);
DOT 1 (-2125 3375);
DOT 1 (-2150 3375);
DOT 1 (-950 2300);
DOT 1 (-1325 3375);
DOT 1 (-975 3675);
DOT 1 (175 1150);
DOT 1 (950 1150);
DOT 1 (1000 1150);
DOT 1 (200 2600);
DOT 1 (175 3975);
DOT 1 (975 2600);
DOT 1 (1000 2600);
DOT 1 (950 3975);
DOT 1 (1125 3975);
DOT 1 (2475 850);
DOT 1 (2500 850);
DOT 1 (3300 850);
DOT 1 (2500 2300);
DOT 1 (2525 2300);
DOT 1 (3375 2300);
DOT 1 (2475 3675);
DOT 1 (2500 3675);
DOT 1 (3325 3675);
DOT 1 (3650 1150);
DOT 1 (4800 1450);
DOT 1 (3675 2600);
DOT 1 (3650 3975);
DOT 1 (4825 2900);
DOT 1 (4800 4275);
DOT 1 (5575 1450);
DOT 1 (5750 1450);
DOT 1 (5600 2900);
DOT 1 (5775 2900);
DOT 1 (5575 4275);
DOT 1 (5650 4275);
QUIT
